G04 ================== begin FILE IDENTIFICATION RECORD ==================*
G04 Layout Name:  15105-sa.brd*
G04 Film Name:    L8*
G04 File Format:  Gerber RS274X*
G04 File Origin:  Cadence Allegro 16.5-S056*
G04 Origin Date:  Wed Nov 16 02:02:29 2016*
G04 *
G04 Layer:  VIA CLASS/BOTTOM*
G04 Layer:  PIN/BOTTOM*
G04 Layer:  ETCH/BOTTOM*
G04 Layer:  DRAWING FORMAT/LAYER_PCB_STORY*
G04 Layer:  DRAWING FORMAT/LAYER_L8*
G04 *
G04 Offset:    (0.00 0.00)*
G04 Mirror:    No*
G04 Mode:      Positive*
G04 Rotation:  0*
G04 FullContactRelief:  No*
G04 UndefLineWidth:     6.00*
G04 ================== end FILE IDENTIFICATION RECORD ====================*
%FSLAX35Y35*MOIN*%
%IR0*IPPOS*OFA0.00000B0.00000*MIA0B0*SFA1.00000B1.00000*%
%AMMACRO37*
4,1,40,.011,.007,
.011,-.007,
.010939,-.007695,
.010759,-.008368,
.010464,-.009,
.010064,-.009571,
.009571,-.010064,
.009,-.010464,
.008368,-.010759,
.007695,-.010939,
.007,-.011,
-.007,-.011,
-.007695,-.010939,
-.008368,-.010759,
-.009,-.010464,
-.009571,-.010064,
-.010064,-.009571,
-.010464,-.009,
-.010759,-.008368,
-.010939,-.007695,
-.011,-.007,
-.011,.007,
-.010939,.007695,
-.010759,.008368,
-.010464,.009,
-.010064,.009571,
-.009571,.010064,
-.009,.010464,
-.008368,.010759,
-.007695,.010939,
-.007,.011,
.007,.011,
.007695,.010939,
.008368,.010759,
.009,.010464,
.009571,.010064,
.010064,.009571,
.010464,.009,
.010759,.008368,
.010939,.007695,
.011,.007,
0.0*
%
%ADD37MACRO37*%
%AMMACRO49*
4,1,40,.013,-.017,
-.013,-.017,
-.013695,-.016939,
-.014368,-.016759,
-.015,-.016464,
-.015571,-.016064,
-.016064,-.015571,
-.016464,-.015,
-.016759,-.014368,
-.016939,-.013695,
-.017,-.013,
-.017,.013,
-.016939,.013695,
-.016759,.014368,
-.016464,.015,
-.016064,.015571,
-.015571,.016064,
-.015,.016464,
-.014368,.016759,
-.013695,.016939,
-.013,.017,
.013,.017,
.013695,.016939,
.014368,.016759,
.015,.016464,
.015571,.016064,
.016064,.015571,
.016464,.015,
.016759,.014368,
.016939,.013695,
.017,.013,
.017,-.013,
.016939,-.013695,
.016759,-.014368,
.016464,-.015,
.016064,-.015571,
.015571,-.016064,
.015,-.016464,
.014368,-.016759,
.013695,-.016939,
.013,-.017,
0.0*
%
%ADD49MACRO49*%
%AMMACRO25*
4,1,40,-.017,-.013,
-.017,.013,
-.016939,.013695,
-.016759,.014368,
-.016464,.015,
-.016064,.015571,
-.015571,.016064,
-.015,.016464,
-.014368,.016759,
-.013695,.016939,
-.013,.017,
.013,.017,
.013695,.016939,
.014368,.016759,
.015,.016464,
.015571,.016064,
.016064,.015571,
.016464,.015,
.016759,.014368,
.016939,.013695,
.017,.013,
.017,-.013,
.016939,-.013695,
.016759,-.014368,
.016464,-.015,
.016064,-.015571,
.015571,-.016064,
.015,-.016464,
.014368,-.016759,
.013695,-.016939,
.013,-.017,
-.013,-.017,
-.013695,-.016939,
-.014368,-.016759,
-.015,-.016464,
-.015571,-.016064,
-.016064,-.015571,
-.016464,-.015,
-.016759,-.014368,
-.016939,-.013695,
-.017,-.013,
0.0*
%
%ADD25MACRO25*%
%ADD10C,.01*%
%ADD11C,.02*%
%ADD35C,.022*%
%ADD17C,.04*%
%ADD63C,.05*%
%AMMACRO62*
4,1,40,-.007,-.004,
-.007,.004,
-.00697,.004347,
-.006879,.004684,
-.006732,.005,
-.006532,.005286,
-.006286,.005532,
-.006,.005732,
-.005684,.005879,
-.005347,.00597,
-.005,.006,
.005,.006,
.005347,.00597,
.005684,.005879,
.006,.005732,
.006286,.005532,
.006532,.005286,
.006732,.005,
.006879,.004684,
.00697,.004347,
.007,.004,
.007,-.004,
.00697,-.004347,
.006879,-.004684,
.006732,-.005,
.006532,-.005286,
.006286,-.005532,
.006,-.005732,
.005684,-.005879,
.005347,-.00597,
.005,-.006,
-.005,-.006,
-.005347,-.00597,
-.005684,-.005879,
-.006,-.005732,
-.006286,-.005532,
-.006532,-.005286,
-.006732,-.005,
-.006879,-.004684,
-.00697,-.004347,
-.007,-.004,
0.0*
%
%ADD62MACRO62*%
%AMMACRO64*
4,1,40,-.004,.007,
.004,.007,
.004347,.00697,
.004684,.006879,
.005,.006732,
.005286,.006532,
.005532,.006286,
.005732,.006,
.005879,.005684,
.00597,.005347,
.006,.005,
.006,-.005,
.00597,-.005347,
.005879,-.005684,
.005732,-.006,
.005532,-.006286,
.005286,-.006532,
.005,-.006732,
.004684,-.006879,
.004347,-.00697,
.004,-.007,
-.004,-.007,
-.004347,-.00697,
-.004684,-.006879,
-.005,-.006732,
-.005286,-.006532,
-.005532,-.006286,
-.005732,-.006,
-.005879,-.005684,
-.00597,-.005347,
-.006,-.005,
-.006,.005,
-.00597,.005347,
-.005879,.005684,
-.005732,.006,
-.005532,.006286,
-.005286,.006532,
-.005,.006732,
-.004684,.006879,
-.004347,.00697,
-.004,.007,
0.0*
%
%ADD64MACRO64*%
%ADD18C,.052*%
%ADD54C,.036*%
%ADD38C,.018*%
%ADD34C,.054*%
%ADD15C,.028*%
%ADD56C,.029*%
%AMMACRO55*
4,1,42,.01182,.09815,
.028621,.094612,
.044553,.08821,
.059131,.079139,
.071913,.067674,
.082509,.054164,
.090599,.039019,
.095935,.022699,
.098357,.005701,
.09779,-.01146,
.094252,-.028261,
.08785,-.044193,
.078779,-.058771,
.067314,-.071553,
.053804,-.082149,
.038659,-.090239,
.022339,-.095575,
.005341,-.097997,
-.01182,-.09743,
-.028621,-.093892,
-.044553,-.08749,
-.059131,-.078419,
-.071913,-.066954,
-.082509,-.053444,
-.090599,-.038299,
-.095935,-.021979,
-.098357,-.004981,
-.09779,.01218,
-.094252,.028981,
-.08785,.044913,
-.078779,.059491,
-.067314,.072273,
-.053804,.082869,
-.038659,.090959,
-.022339,.096295,
-.01182,.09815,
-.008112,.096406,
-.004157,.095333,
-.000076,.094962,
.004007,.095306,
.007968,.096354,
.011688,.098074,
.01182,.09815,
0.0*
%
%ADD55MACRO55*%
%ADD44C,.056*%
%ADD12C,.066*%
%ADD53C,.058*%
%ADD13C,.078*%
%AMMACRO59*
4,1,40,.0225,.007,
.022378,.008389,
.022018,.009736,
.021428,.011,
.020628,.012142,
.019642,.013128,
.0185,.013928,
.017236,.014518,
.015889,.014878,
.0145,.015,
-.0145,.015,
-.015889,.014878,
-.017236,.014518,
-.0185,.013928,
-.019642,.013128,
-.020628,.012142,
-.021428,.011,
-.022018,.009736,
-.022378,.008389,
-.0225,.007,
-.0225,-.007,
-.022378,-.008389,
-.022018,-.009736,
-.021428,-.011,
-.020628,-.012142,
-.019642,-.013128,
-.0185,-.013928,
-.017236,-.014518,
-.015889,-.014878,
-.0145,-.015,
.0145,-.015,
.015889,-.014878,
.017236,-.014518,
.0185,-.013928,
.019642,-.013128,
.020628,-.012142,
.021428,-.011,
.022018,-.009736,
.022378,-.008389,
.0225,-.007,
.0225,.007,
0.0*
%
%ADD59MACRO59*%
%AMMACRO29*
4,1,40,.007,-.011,
-.007,-.011,
-.007695,-.010939,
-.008368,-.010759,
-.009,-.010464,
-.009571,-.010064,
-.010064,-.009571,
-.010464,-.009,
-.010759,-.008368,
-.010939,-.007695,
-.011,-.007,
-.011,.007,
-.010939,.007695,
-.010759,.008368,
-.010464,.009,
-.010064,.009571,
-.009571,.010064,
-.009,.010464,
-.008368,.010759,
-.007695,.010939,
-.007,.011,
.007,.011,
.007695,.010939,
.008368,.010759,
.009,.010464,
.009571,.010064,
.010064,.009571,
.010464,.009,
.010759,.008368,
.010939,.007695,
.011,.007,
.011,-.007,
.010939,-.007695,
.010759,-.008368,
.010464,-.009,
.010064,-.009571,
.009571,-.010064,
.009,-.010464,
.008368,-.010759,
.007695,-.010939,
.007,-.011,
0.0*
%
%ADD29MACRO29*%
%AMMACRO23*
4,1,40,-.011,-.007,
-.011,.007,
-.010939,.007695,
-.010759,.008368,
-.010464,.009,
-.010064,.009571,
-.009571,.010064,
-.009,.010464,
-.008368,.010759,
-.007695,.010939,
-.007,.011,
.007,.011,
.007695,.010939,
.008368,.010759,
.009,.010464,
.009571,.010064,
.010064,.009571,
.010464,.009,
.010759,.008368,
.010939,.007695,
.011,.007,
.011,-.007,
.010939,-.007695,
.010759,-.008368,
.010464,-.009,
.010064,-.009571,
.009571,-.010064,
.009,-.010464,
.008368,-.010759,
.007695,-.010939,
.007,-.011,
-.007,-.011,
-.007695,-.010939,
-.008368,-.010759,
-.009,-.010464,
-.009571,-.010064,
-.010064,-.009571,
-.010464,-.009,
-.010759,-.008368,
-.010939,-.007695,
-.011,-.007,
0.0*
%
%ADD23MACRO23*%
%AMMACRO20*
4,1,40,-.012,-.008,
-.012,.008,
-.011939,.008695,
-.011759,.009368,
-.011464,.01,
-.011064,.010571,
-.010571,.011064,
-.01,.011464,
-.009368,.011759,
-.008695,.011939,
-.008,.012,
.008,.012,
.008695,.011939,
.009368,.011759,
.01,.011464,
.010571,.011064,
.011064,.010571,
.011464,.01,
.011759,.009368,
.011939,.008695,
.012,.008,
.012,-.008,
.011939,-.008695,
.011759,-.009368,
.011464,-.01,
.011064,-.010571,
.010571,-.011064,
.01,-.011464,
.009368,-.011759,
.008695,-.011939,
.008,-.012,
-.008,-.012,
-.008695,-.011939,
-.009368,-.011759,
-.01,-.011464,
-.010571,-.011064,
-.011064,-.010571,
-.011464,-.01,
-.011759,-.009368,
-.011939,-.008695,
-.012,-.008,
0.0*
%
%ADD20MACRO20*%
%AMMACRO32*
4,1,40,-.008,.012,
.008,.012,
.008695,.011939,
.009368,.011759,
.01,.011464,
.010571,.011064,
.011064,.010571,
.011464,.01,
.011759,.009368,
.011939,.008695,
.012,.008,
.012,-.008,
.011939,-.008695,
.011759,-.009368,
.011464,-.01,
.011064,-.010571,
.010571,-.011064,
.01,-.011464,
.009368,-.011759,
.008695,-.011939,
.008,-.012,
-.008,-.012,
-.008695,-.011939,
-.009368,-.011759,
-.01,-.011464,
-.010571,-.011064,
-.011064,-.010571,
-.011464,-.01,
-.011759,-.009368,
-.011939,-.008695,
-.012,-.008,
-.012,.008,
-.011939,.008695,
-.011759,.009368,
-.011464,.01,
-.011064,.010571,
-.010571,.011064,
-.01,.011464,
-.009368,.011759,
-.008695,.011939,
-.008,.012,
0.0*
%
%ADD32MACRO32*%
%AMMACRO48*
4,1,40,-.013,.017,
.013,.017,
.013695,.016939,
.014368,.016759,
.015,.016464,
.015571,.016064,
.016064,.015571,
.016464,.015,
.016759,.014368,
.016939,.013695,
.017,.013,
.017,-.013,
.016939,-.013695,
.016759,-.014368,
.016464,-.015,
.016064,-.015571,
.015571,-.016064,
.015,-.016464,
.014368,-.016759,
.013695,-.016939,
.013,-.017,
-.013,-.017,
-.013695,-.016939,
-.014368,-.016759,
-.015,-.016464,
-.015571,-.016064,
-.016064,-.015571,
-.016464,-.015,
-.016759,-.014368,
-.016939,-.013695,
-.017,-.013,
-.017,.013,
-.016939,.013695,
-.016759,.014368,
-.016464,.015,
-.016064,.015571,
-.015571,.016064,
-.015,.016464,
-.014368,.016759,
-.013695,.016939,
-.013,.017,
0.0*
%
%ADD48MACRO48*%
%AMMACRO67*
4,1,40,.017,.013,
.017,-.013,
.016939,-.013695,
.016759,-.014368,
.016464,-.015,
.016064,-.015571,
.015571,-.016064,
.015,-.016464,
.014368,-.016759,
.013695,-.016939,
.013,-.017,
-.013,-.017,
-.013695,-.016939,
-.014368,-.016759,
-.015,-.016464,
-.015571,-.016064,
-.016064,-.015571,
-.016464,-.015,
-.016759,-.014368,
-.016939,-.013695,
-.017,-.013,
-.017,.013,
-.016939,.013695,
-.016759,.014368,
-.016464,.015,
-.016064,.015571,
-.015571,.016064,
-.015,.016464,
-.014368,.016759,
-.013695,.016939,
-.013,.017,
.013,.017,
.013695,.016939,
.014368,.016759,
.015,.016464,
.015571,.016064,
.016064,.015571,
.016464,.015,
.016759,.014368,
.016939,.013695,
.017,.013,
0.0*
%
%ADD67MACRO67*%
%AMMACRO30*
4,1,40,.007,-.011,
-.007,-.011,
-.007695,-.010939,
-.008368,-.010759,
-.009,-.010464,
-.009571,-.010064,
-.010064,-.009571,
-.010464,-.009,
-.010759,-.008368,
-.010939,-.007695,
-.011,-.007,
-.011,.007,
-.010939,.007695,
-.010759,.008368,
-.010464,.009,
-.010064,.009571,
-.009571,.010064,
-.009,.010464,
-.008368,.010759,
-.007695,.010939,
-.007,.011,
.007,.011,
.007695,.010939,
.008368,.010759,
.009,.010464,
.009571,.010064,
.010064,.009571,
.010464,.009,
.010759,.008368,
.010939,.007695,
.011,.007,
.011,-.007,
.010939,-.007695,
.010759,-.008368,
.010464,-.009,
.010064,-.009571,
.009571,-.010064,
.009,-.010464,
.008368,-.010759,
.007695,-.010939,
.007,-.011,
0.0*
%
%ADD30MACRO30*%
%AMMACRO24*
4,1,40,-.011,-.007,
-.011,.007,
-.010939,.007695,
-.010759,.008368,
-.010464,.009,
-.010064,.009571,
-.009571,.010064,
-.009,.010464,
-.008368,.010759,
-.007695,.010939,
-.007,.011,
.007,.011,
.007695,.010939,
.008368,.010759,
.009,.010464,
.009571,.010064,
.010064,.009571,
.010464,.009,
.010759,.008368,
.010939,.007695,
.011,.007,
.011,-.007,
.010939,-.007695,
.010759,-.008368,
.010464,-.009,
.010064,-.009571,
.009571,-.010064,
.009,-.010464,
.008368,-.010759,
.007695,-.010939,
.007,-.011,
-.007,-.011,
-.007695,-.010939,
-.008368,-.010759,
-.009,-.010464,
-.009571,-.010064,
-.010064,-.009571,
-.010464,-.009,
-.010759,-.008368,
-.010939,-.007695,
-.011,-.007,
0.0*
%
%ADD24MACRO24*%
%AMMACRO21*
4,1,40,-.012,-.008,
-.012,.008,
-.011939,.008695,
-.011759,.009368,
-.011464,.01,
-.011064,.010571,
-.010571,.011064,
-.01,.011464,
-.009368,.011759,
-.008695,.011939,
-.008,.012,
.008,.012,
.008695,.011939,
.009368,.011759,
.01,.011464,
.010571,.011064,
.011064,.010571,
.011464,.01,
.011759,.009368,
.011939,.008695,
.012,.008,
.012,-.008,
.011939,-.008695,
.011759,-.009368,
.011464,-.01,
.011064,-.010571,
.010571,-.011064,
.01,-.011464,
.009368,-.011759,
.008695,-.011939,
.008,-.012,
-.008,-.012,
-.008695,-.011939,
-.009368,-.011759,
-.01,-.011464,
-.010571,-.011064,
-.011064,-.010571,
-.011464,-.01,
-.011759,-.009368,
-.011939,-.008695,
-.012,-.008,
0.0*
%
%ADD21MACRO21*%
%AMMACRO31*
4,1,40,-.008,.012,
.008,.012,
.008695,.011939,
.009368,.011759,
.01,.011464,
.010571,.011064,
.011064,.010571,
.011464,.01,
.011759,.009368,
.011939,.008695,
.012,.008,
.012,-.008,
.011939,-.008695,
.011759,-.009368,
.011464,-.01,
.011064,-.010571,
.010571,-.011064,
.01,-.011464,
.009368,-.011759,
.008695,-.011939,
.008,-.012,
-.008,-.012,
-.008695,-.011939,
-.009368,-.011759,
-.01,-.011464,
-.010571,-.011064,
-.011064,-.010571,
-.011464,-.01,
-.011759,-.009368,
-.011939,-.008695,
-.012,-.008,
-.012,.008,
-.011939,.008695,
-.011759,.009368,
-.011464,.01,
-.011064,.010571,
-.010571,.011064,
-.01,.011464,
-.009368,.011759,
-.008695,.011939,
-.008,.012,
0.0*
%
%ADD31MACRO31*%
%AMMACRO47*
4,1,40,-.013,.017,
.013,.017,
.013695,.016939,
.014368,.016759,
.015,.016464,
.015571,.016064,
.016064,.015571,
.016464,.015,
.016759,.014368,
.016939,.013695,
.017,.013,
.017,-.013,
.016939,-.013695,
.016759,-.014368,
.016464,-.015,
.016064,-.015571,
.015571,-.016064,
.015,-.016464,
.014368,-.016759,
.013695,-.016939,
.013,-.017,
-.013,-.017,
-.013695,-.016939,
-.014368,-.016759,
-.015,-.016464,
-.015571,-.016064,
-.016064,-.015571,
-.016464,-.015,
-.016759,-.014368,
-.016939,-.013695,
-.017,-.013,
-.017,.013,
-.016939,.013695,
-.016759,.014368,
-.016464,.015,
-.016064,.015571,
-.015571,.016064,
-.015,.016464,
-.014368,.016759,
-.013695,.016939,
-.013,.017,
0.0*
%
%ADD47MACRO47*%
%AMMACRO68*
4,1,40,.017,.013,
.017,-.013,
.016939,-.013695,
.016759,-.014368,
.016464,-.015,
.016064,-.015571,
.015571,-.016064,
.015,-.016464,
.014368,-.016759,
.013695,-.016939,
.013,-.017,
-.013,-.017,
-.013695,-.016939,
-.014368,-.016759,
-.015,-.016464,
-.015571,-.016064,
-.016064,-.015571,
-.016464,-.015,
-.016759,-.014368,
-.016939,-.013695,
-.017,-.013,
-.017,.013,
-.016939,.013695,
-.016759,.014368,
-.016464,.015,
-.016064,.015571,
-.015571,.016064,
-.015,.016464,
-.014368,.016759,
-.013695,.016939,
-.013,.017,
.013,.017,
.013695,.016939,
.014368,.016759,
.015,.016464,
.015571,.016064,
.016064,.015571,
.016464,.015,
.016759,.014368,
.016939,.013695,
.017,.013,
0.0*
%
%ADD68MACRO68*%
%ADD66R,.04X.014*%
%ADD58R,.03X.026*%
%ADD45R,.04X.016*%
%ADD57R,.026X.03*%
%ADD52O,.046X.041*%
%ADD46R,.016X.04*%
%AMMACRO65*
4,1,40,.004,-.007,
-.004,-.007,
-.004347,-.00697,
-.004684,-.006879,
-.005,-.006732,
-.005286,-.006532,
-.005532,-.006286,
-.005732,-.006,
-.005879,-.005684,
-.00597,-.005347,
-.006,-.005,
-.006,.005,
-.00597,.005347,
-.005879,.005684,
-.005732,.006,
-.005532,.006286,
-.005286,.006532,
-.005,.006732,
-.004684,.006879,
-.004347,.00697,
-.004,.007,
.004,.007,
.004347,.00697,
.004684,.006879,
.005,.006732,
.005286,.006532,
.005532,.006286,
.005732,.006,
.005879,.005684,
.00597,.005347,
.006,.005,
.006,-.005,
.00597,-.005347,
.005879,-.005684,
.005732,-.006,
.005532,-.006286,
.005286,-.006532,
.005,-.006732,
.004684,-.006879,
.004347,-.00697,
.004,-.007,
0.0*
%
%ADD65MACRO65*%
%AMMACRO61*
4,1,40,.007,.004,
.007,-.004,
.00697,-.004347,
.006879,-.004684,
.006732,-.005,
.006532,-.005286,
.006286,-.005532,
.006,-.005732,
.005684,-.005879,
.005347,-.00597,
.005,-.006,
-.005,-.006,
-.005347,-.00597,
-.005684,-.005879,
-.006,-.005732,
-.006286,-.005532,
-.006532,-.005286,
-.006732,-.005,
-.006879,-.004684,
-.00697,-.004347,
-.007,-.004,
-.007,.004,
-.00697,.004347,
-.006879,.004684,
-.006732,.005,
-.006532,.005286,
-.006286,.005532,
-.006,.005732,
-.005684,.005879,
-.005347,.00597,
-.005,.006,
.005,.006,
.005347,.00597,
.005684,.005879,
.006,.005732,
.006286,.005532,
.006532,.005286,
.006732,.005,
.006879,.004684,
.00697,.004347,
.007,.004,
0.0*
%
%ADD61MACRO61*%
%ADD41R,.022X.091*%
%ADD33C,.107*%
%ADD16C,.315*%
%ADD14R,.045X.055*%
%ADD51R,.016X.048*%
%ADD22R,.055X.045*%
%ADD19C,.256*%
%AMMACRO69*
4,1,40,-.007,.0225,
-.008389,.022378,
-.009736,.022018,
-.011,.021428,
-.012142,.020628,
-.013128,.019642,
-.013928,.0185,
-.014518,.017236,
-.014878,.015889,
-.015,.0145,
-.015,-.0145,
-.014878,-.015889,
-.014518,-.017236,
-.013928,-.0185,
-.013128,-.019642,
-.012142,-.020628,
-.011,-.021428,
-.009736,-.022018,
-.008389,-.022378,
-.007,-.0225,
.007,-.0225,
.008389,-.022378,
.009736,-.022018,
.011,-.021428,
.012142,-.020628,
.013128,-.019642,
.013928,-.0185,
.014518,-.017236,
.014878,-.015889,
.015,-.0145,
.015,.0145,
.014878,.015889,
.014518,.017236,
.013928,.0185,
.013128,.019642,
.012142,.020628,
.011,.021428,
.009736,.022018,
.008389,.022378,
.007,.0225,
-.007,.0225,
0.0*
%
%ADD69MACRO69*%
%AMMACRO60*
4,1,40,-.012,-.024,
.012,-.024,
.013389,-.023878,
.014736,-.023518,
.016,-.022928,
.017142,-.022128,
.018128,-.021142,
.018928,-.02,
.019518,-.018736,
.019878,-.017389,
.02,-.016,
.02,.016,
.019878,.017389,
.019518,.018736,
.018928,.02,
.018128,.021142,
.017142,.022128,
.016,.022928,
.014736,.023518,
.013389,.023878,
.012,.024,
-.012,.024,
-.013389,.023878,
-.014736,.023518,
-.016,.022928,
-.017142,.022128,
-.018128,.021142,
-.018928,.02,
-.019518,.018736,
-.019878,.017389,
-.02,.016,
-.02,-.016,
-.019878,-.017389,
-.019518,-.018736,
-.018928,-.02,
-.018128,-.021142,
-.017142,-.022128,
-.016,-.022928,
-.014736,-.023518,
-.013389,-.023878,
-.012,-.024,
0.0*
%
%ADD60MACRO60*%
%AMMACRO42*
4,1,40,.012,.008,
.012,-.008,
.011939,-.008695,
.011759,-.009368,
.011464,-.01,
.011064,-.010571,
.010571,-.011064,
.01,-.011464,
.009368,-.011759,
.008695,-.011939,
.008,-.012,
-.008,-.012,
-.008695,-.011939,
-.009368,-.011759,
-.01,-.011464,
-.010571,-.011064,
-.011064,-.010571,
-.011464,-.01,
-.011759,-.009368,
-.011939,-.008695,
-.012,-.008,
-.012,.008,
-.011939,.008695,
-.011759,.009368,
-.011464,.01,
-.011064,.010571,
-.010571,.011064,
-.01,.011464,
-.009368,.011759,
-.008695,.011939,
-.008,.012,
.008,.012,
.008695,.011939,
.009368,.011759,
.01,.011464,
.010571,.011064,
.011064,.010571,
.011464,.01,
.011759,.009368,
.011939,.008695,
.012,.008,
0.0*
%
%ADD42MACRO42*%
%AMMACRO39*
4,1,40,.008,-.012,
-.008,-.012,
-.008695,-.011939,
-.009368,-.011759,
-.01,-.011464,
-.010571,-.011064,
-.011064,-.010571,
-.011464,-.01,
-.011759,-.009368,
-.011939,-.008695,
-.012,-.008,
-.012,.008,
-.011939,.008695,
-.011759,.009368,
-.011464,.01,
-.011064,.010571,
-.010571,.011064,
-.01,.011464,
-.009368,.011759,
-.008695,.011939,
-.008,.012,
.008,.012,
.008695,.011939,
.009368,.011759,
.01,.011464,
.010571,.011064,
.011064,.010571,
.011464,.01,
.011759,.009368,
.011939,.008695,
.012,.008,
.012,-.008,
.011939,-.008695,
.011759,-.009368,
.011464,-.01,
.011064,-.010571,
.010571,-.011064,
.01,-.011464,
.009368,-.011759,
.008695,-.011939,
.008,-.012,
0.0*
%
%ADD39MACRO39*%
%AMMACRO27*
4,1,40,-.007,.011,
.007,.011,
.007695,.010939,
.008368,.010759,
.009,.010464,
.009571,.010064,
.010064,.009571,
.010464,.009,
.010759,.008368,
.010939,.007695,
.011,.007,
.011,-.007,
.010939,-.007695,
.010759,-.008368,
.010464,-.009,
.010064,-.009571,
.009571,-.010064,
.009,-.010464,
.008368,-.010759,
.007695,-.010939,
.007,-.011,
-.007,-.011,
-.007695,-.010939,
-.008368,-.010759,
-.009,-.010464,
-.009571,-.010064,
-.010064,-.009571,
-.010464,-.009,
-.010759,-.008368,
-.010939,-.007695,
-.011,-.007,
-.011,.007,
-.010939,.007695,
-.010759,.008368,
-.010464,.009,
-.010064,.009571,
-.009571,.010064,
-.009,.010464,
-.008368,.010759,
-.007695,.010939,
-.007,.011,
0.0*
%
%ADD27MACRO27*%
%AMMACRO36*
4,1,40,.011,.007,
.011,-.007,
.010939,-.007695,
.010759,-.008368,
.010464,-.009,
.010064,-.009571,
.009571,-.010064,
.009,-.010464,
.008368,-.010759,
.007695,-.010939,
.007,-.011,
-.007,-.011,
-.007695,-.010939,
-.008368,-.010759,
-.009,-.010464,
-.009571,-.010064,
-.010064,-.009571,
-.010464,-.009,
-.010759,-.008368,
-.010939,-.007695,
-.011,-.007,
-.011,.007,
-.010939,.007695,
-.010759,.008368,
-.010464,.009,
-.010064,.009571,
-.009571,.010064,
-.009,.010464,
-.008368,.010759,
-.007695,.010939,
-.007,.011,
.007,.011,
.007695,.010939,
.008368,.010759,
.009,.010464,
.009571,.010064,
.010064,.009571,
.010464,.009,
.010759,.008368,
.010939,.007695,
.011,.007,
0.0*
%
%ADD36MACRO36*%
%AMMACRO50*
4,1,40,.013,-.017,
-.013,-.017,
-.013695,-.016939,
-.014368,-.016759,
-.015,-.016464,
-.015571,-.016064,
-.016064,-.015571,
-.016464,-.015,
-.016759,-.014368,
-.016939,-.013695,
-.017,-.013,
-.017,.013,
-.016939,.013695,
-.016759,.014368,
-.016464,.015,
-.016064,.015571,
-.015571,.016064,
-.015,.016464,
-.014368,.016759,
-.013695,.016939,
-.013,.017,
.013,.017,
.013695,.016939,
.014368,.016759,
.015,.016464,
.015571,.016064,
.016064,.015571,
.016464,.015,
.016759,.014368,
.016939,.013695,
.017,.013,
.017,-.013,
.016939,-.013695,
.016759,-.014368,
.016464,-.015,
.016064,-.015571,
.015571,-.016064,
.015,-.016464,
.014368,-.016759,
.013695,-.016939,
.013,-.017,
0.0*
%
%ADD50MACRO50*%
%AMMACRO26*
4,1,40,-.017,-.013,
-.017,.013,
-.016939,.013695,
-.016759,.014368,
-.016464,.015,
-.016064,.015571,
-.015571,.016064,
-.015,.016464,
-.014368,.016759,
-.013695,.016939,
-.013,.017,
.013,.017,
.013695,.016939,
.014368,.016759,
.015,.016464,
.015571,.016064,
.016064,.015571,
.016464,.015,
.016759,.014368,
.016939,.013695,
.017,.013,
.017,-.013,
.016939,-.013695,
.016759,-.014368,
.016464,-.015,
.016064,-.015571,
.015571,-.016064,
.015,-.016464,
.014368,-.016759,
.013695,-.016939,
.013,-.017,
-.013,-.017,
-.013695,-.016939,
-.014368,-.016759,
-.015,-.016464,
-.015571,-.016064,
-.016064,-.015571,
-.016464,-.015,
-.016759,-.014368,
-.016939,-.013695,
-.017,-.013,
0.0*
%
%ADD26MACRO26*%
%AMMACRO43*
4,1,40,.012,.008,
.012,-.008,
.011939,-.008695,
.011759,-.009368,
.011464,-.01,
.011064,-.010571,
.010571,-.011064,
.01,-.011464,
.009368,-.011759,
.008695,-.011939,
.008,-.012,
-.008,-.012,
-.008695,-.011939,
-.009368,-.011759,
-.01,-.011464,
-.010571,-.011064,
-.011064,-.010571,
-.011464,-.01,
-.011759,-.009368,
-.011939,-.008695,
-.012,-.008,
-.012,.008,
-.011939,.008695,
-.011759,.009368,
-.011464,.01,
-.011064,.010571,
-.010571,.011064,
-.01,.011464,
-.009368,.011759,
-.008695,.011939,
-.008,.012,
.008,.012,
.008695,.011939,
.009368,.011759,
.01,.011464,
.010571,.011064,
.011064,.010571,
.011464,.01,
.011759,.009368,
.011939,.008695,
.012,.008,
0.0*
%
%ADD43MACRO43*%
%AMMACRO40*
4,1,40,.008,-.012,
-.008,-.012,
-.008695,-.011939,
-.009368,-.011759,
-.01,-.011464,
-.010571,-.011064,
-.011064,-.010571,
-.011464,-.01,
-.011759,-.009368,
-.011939,-.008695,
-.012,-.008,
-.012,.008,
-.011939,.008695,
-.011759,.009368,
-.011464,.01,
-.011064,.010571,
-.010571,.011064,
-.01,.011464,
-.009368,.011759,
-.008695,.011939,
-.008,.012,
.008,.012,
.008695,.011939,
.009368,.011759,
.01,.011464,
.010571,.011064,
.011064,.010571,
.011464,.01,
.011759,.009368,
.011939,.008695,
.012,.008,
.012,-.008,
.011939,-.008695,
.011759,-.009368,
.011464,-.01,
.011064,-.010571,
.010571,-.011064,
.01,-.011464,
.009368,-.011759,
.008695,-.011939,
.008,-.012,
0.0*
%
%ADD40MACRO40*%
%AMMACRO28*
4,1,40,-.007,.011,
.007,.011,
.007695,.010939,
.008368,.010759,
.009,.010464,
.009571,.010064,
.010064,.009571,
.010464,.009,
.010759,.008368,
.010939,.007695,
.011,.007,
.011,-.007,
.010939,-.007695,
.010759,-.008368,
.010464,-.009,
.010064,-.009571,
.009571,-.010064,
.009,-.010464,
.008368,-.010759,
.007695,-.010939,
.007,-.011,
-.007,-.011,
-.007695,-.010939,
-.008368,-.010759,
-.009,-.010464,
-.009571,-.010064,
-.010064,-.009571,
-.010464,-.009,
-.010759,-.008368,
-.010939,-.007695,
-.011,-.007,
-.011,.007,
-.010939,.007695,
-.010759,.008368,
-.010464,.009,
-.010064,.009571,
-.009571,.010064,
-.009,.010464,
-.008368,.010759,
-.007695,.010939,
-.007,.011,
0.0*
%
%ADD28MACRO28*%
%ADD70C,.012*%
%ADD71C,.014*%
%ADD72C,.015*%
%ADD73C,.016*%
%ADD74C,.004*%
%ADD75C,.006*%
%ADD76C,.00474*%
%ADD77C,.00538*%
%ADD78C,.00475*%
%ADD105R,.01801X.008*%
%ADD100R,.019X.008*%
%ADD97R,.008X.019*%
%ADD88C,.06004*%
%ADD104R,.01802X.008*%
%ADD99C,.08004*%
%ADD85C,.04404*%
%ADD101C,.02704*%
%ADD84C,.09004*%
%ADD98C,.06404*%
%ADD83C,.09204*%
%ADD82C,.05604*%
%ADD87C,.07804*%
%ADD79C,.11004*%
%ADD86C,.13104*%
%ADD80C,.15204*%
%ADD96R,.008X.008*%
%ADD93C,.34362*%
%ADD89C,.33904*%
%ADD90C,.34184*%
%ADD81C,.29532*%
%ADD103C,.34492*%
%ADD102C,.34726*%
%ADD92C,.34574*%
%ADD95C,.33918*%
%ADD91C,.33936*%
%ADD94C,.34838*%
G75*
%LPD*%
G75*
G36*
G01X486762Y-16681D02*
G02X481892Y-11811I0J4870D01*
G01Y-7874D01*
G03X471014Y3004I-10878J0D01*
G01X212402D01*
G02X207532Y7874I0J4870D01*
G01Y94528D01*
G03X196654Y105406I-10878J0D01*
G01X7874D01*
G02X3004Y110276I0J4870D01*
G01Y836614D01*
G02X3937Y837547I933J0D01*
G01X97448D01*
Y832551D01*
X40370D01*
X32478Y824659D01*
G02X31857Y824729I-283J283D01*
G03X25071Y816727I-4657J-2929D01*
G01Y810287D01*
X25040Y810238D01*
G03X25071Y792076I14330J-9057D01*
G01Y755462D01*
G03Y753338I1929J-1062D01*
G01Y742348D01*
X46768Y720651D01*
X54388D01*
Y720448D01*
G03X58792I2202J-38D01*
G01Y720651D01*
X104791D01*
X104840Y720522D01*
G03X105314Y719772I2060J777D01*
G02X105329Y719234I-288J-277D01*
G03X108586Y719328I1671J-1434D01*
G02X108571Y719866I288J277D01*
G03X108960Y720522I-1671J1434D01*
G01X109009Y720651D01*
X123567D01*
X126149Y718069D01*
Y709103D01*
G02X125503Y708787I-400J0D01*
G03Y705313I-1353J-1737D01*
G02X126149Y704997I246J-316D01*
G01Y694134D01*
X123221Y691206D01*
X83500D01*
X80734Y688440D01*
X67464D01*
G02X67139Y689073I0J400D01*
G03X63561I-1789J1283D01*
G02X63236Y688440I-325J-233D01*
G01X53460D01*
X50694Y691206D01*
X25931D01*
X20077Y685352D01*
Y656250D01*
X28687Y647640D01*
X87061D01*
X98942Y635759D01*
Y568968D01*
X95523Y565549D01*
X93504D01*
X93478Y565556D01*
G03X93060Y565612I-420J-1546D01*
G01X91660D01*
G03X91365Y565584I3J-1602D01*
G01X91261Y565565D01*
X89409Y567417D01*
Y568522D01*
X89420Y568553D01*
G03Y569983I-2083J715D01*
G01X89409Y570014D01*
Y570560D01*
X89120D01*
G03X85554I-1783J-1292D01*
G01X79420D01*
X75830Y566970D01*
X62660D01*
X60770Y565080D01*
Y547221D01*
X57874Y544325D01*
Y508809D01*
X55628Y506563D01*
X55625Y506560D01*
G03X55249Y505998I975J-1059D01*
G01X55234Y505957D01*
X46862Y497585D01*
Y497582D01*
X46040Y496760D01*
X45460D01*
X40600Y491900D01*
Y451100D01*
X59200Y432500D01*
Y386190D01*
X62123Y383267D01*
Y378359D01*
X56410Y372646D01*
Y356390D01*
X60950Y351850D01*
Y344627D01*
G03X60876Y340831I1450J-1927D01*
G01X60950Y340771D01*
Y340600D01*
X61100D01*
X61700Y340000D01*
X83200D01*
X90418Y332781D01*
Y323218D01*
X89800Y322600D01*
X85000D01*
X84990Y322610D01*
X79435D01*
X79409Y322779D01*
G03X77421Y324482I-1988J-309D01*
G01X74221D01*
G03X74106Y324478I12J-2012D01*
G01X74017Y324473D01*
X72190Y326300D01*
X70400D01*
X70200Y326100D01*
X45400D01*
X41400Y322100D01*
Y316700D01*
X40000Y315300D01*
X37110D01*
X35255Y313445D01*
Y306455D01*
X33900Y305100D01*
X32876D01*
X32827Y305130D01*
G03X30497I-1165J-1868D01*
G01X30448Y305100D01*
X30200D01*
X29700Y304600D01*
Y304263D01*
X29680Y304221D01*
G03X30706Y301279I1982J-959D01*
G01X30736Y301264D01*
X36600Y295400D01*
Y282452D01*
X36248D01*
Y281148D01*
X35800Y280700D01*
Y272752D01*
X35448D01*
Y270748D01*
X34200Y269500D01*
Y260900D01*
X37700Y257400D01*
X52700D01*
X54500Y259200D01*
X62388D01*
G03X64463Y258864I1312J1525D01*
G01X64586Y258914D01*
X65898Y257602D01*
Y255000D01*
G03X70302I2202J0D01*
G01Y260902D01*
X73700Y264300D01*
X89000D01*
X91091Y262209D01*
X97091D01*
X103900Y255400D01*
Y239747D01*
X163449Y180198D01*
Y176043D01*
G02X162965Y175652I-400J0D01*
G03Y171348I-465J-2152D01*
G02X163449Y170957I84J-391D01*
G01Y157663D01*
G02X162934Y157280I-400J0D01*
G03Y149806I-1123J-3737D01*
G02X163449Y149423I115J-383D01*
G01Y128593D01*
X175537Y116505D01*
X212862D01*
X212864Y116504D01*
X212889D01*
X215318Y114074D01*
Y114049D01*
X215320Y114047D01*
Y70670D01*
X226430Y59560D01*
X259420D01*
X266710Y66850D01*
Y104225D01*
G03Y106475I-1893J1125D01*
G01Y112510D01*
X273200Y119000D01*
X411919D01*
X419587Y111332D01*
X436200D01*
X454332Y93200D01*
X464145D01*
X465325Y92020D01*
X465489D01*
X497100Y60409D01*
Y21500D01*
X508800Y9800D01*
X514119D01*
X521132Y2787D01*
X549405D01*
X549970Y3352D01*
X698911D01*
X716580Y-14318D01*
X720418D01*
X721700Y-15600D01*
X779933D01*
X780436Y-16102D01*
X825576D01*
X826079Y-15600D01*
X899085D01*
X903000Y-11685D01*
X1025971D01*
G03X1029473I1751J2560D01*
G01X1052743D01*
G03X1056245I1751J2560D01*
G01X1095096D01*
X1095364Y-11416D01*
X1095367D01*
X1113514Y6730D01*
X1286935D01*
X1286937Y6732D01*
X1293112D01*
X1307060Y20680D01*
Y43947D01*
X1307062Y43948D01*
Y67552D01*
X1307060Y67553D01*
Y119045D01*
X1307962Y119947D01*
Y137382D01*
X1314515Y143935D01*
G02X1315198Y143648I283J-282D01*
G03X1318576Y145482I2202J-28D01*
G02X1318451Y146034I213J338D01*
G03X1318671Y147931I-1861J1177D01*
G01X1318630Y148050D01*
X1324796Y154216D01*
X1362926D01*
X1363874Y155164D01*
X1385497D01*
X1392000Y161667D01*
Y372426D01*
X1389364Y375062D01*
Y375298D01*
X1318184Y446478D01*
X1317948D01*
X1315842Y448584D01*
X574028D01*
X541483Y416039D01*
X372388D01*
X350691Y437736D01*
Y490083D01*
X333644Y507130D01*
Y544668D01*
X323312Y555000D01*
X307815D01*
X289734Y536919D01*
X274237D01*
X265283Y545873D01*
X244447D01*
X231997Y558323D01*
X232000Y558411D01*
G03X229711Y560700I-2200J89D01*
G01X229623Y560697D01*
X205530Y584790D01*
X197265D01*
X179013Y603042D01*
Y637137D01*
X191324Y649448D01*
X259600D01*
X269309Y639739D01*
X269303Y639648D01*
G03X273698Y639369I2197J-148D01*
G01X273703Y639445D01*
X276217Y641959D01*
Y651601D01*
X278628Y654012D01*
X788754D01*
X860043Y582723D01*
X1274343D01*
X1365261Y673641D01*
Y784874D01*
G03Y817488I-4631J16307D01*
G01Y832958D01*
G02X1359454Y836172I3242J12711D01*
G01Y836482D01*
X1359340Y836597D01*
Y838696D01*
X1355860Y842176D01*
G02X1355386Y845669I12644J3494D01*
G01Y866301D01*
X1360382D01*
Y845669D01*
G03X1368504Y837547I8122J0D01*
G01X1396063D01*
G02X1396996Y836614I0J-933D01*
G01Y77025D01*
G02X1396600Y76626I-400J1D01*
G03X1391681Y71654I54J-4972D01*
G01Y40157D01*
G03X1396600Y35185I4973J0D01*
G02X1396996Y34786I-4J-400D01*
G01Y5696D01*
X1394800Y3500D01*
X1307100D01*
X1302900Y-700D01*
Y-15481D01*
X1301700Y-16681D01*
X486762D01*
G37*
G36*
G01X52730Y300314D02*
Y299859D01*
X52713Y299820D01*
G03X52576Y299171I1464J-648D01*
G01Y297571D01*
Y297530D01*
G02X52354Y297326I-200J-5D01*
G03X52178Y297336I-179J-1592D01*
G01X50578D01*
G03X50327Y297316I1J-1602D01*
G01X50226Y297300D01*
X49717Y297809D01*
X46858D01*
X45763Y296714D01*
Y295418D01*
X45759Y295398D01*
G03Y294482I2153J-458D01*
G01X45763Y294462D01*
Y288437D01*
X51100Y283100D01*
Y280500D01*
X50100Y279500D01*
Y277900D01*
X51700Y276300D01*
Y258750D01*
X51552Y258602D01*
X38598D01*
X36700Y260500D01*
Y270301D01*
X37002Y270602D01*
Y272058D01*
G03Y274442I-1852J1192D01*
G01Y280202D01*
X37802Y281002D01*
Y291530D01*
X41100Y294828D01*
Y298837D01*
X41108Y298865D01*
G03Y300135I-2108J635D01*
G01X41100Y300163D01*
Y303900D01*
X39800Y305200D01*
X37600D01*
X37200Y305600D01*
Y311000D01*
X38350Y312150D01*
X42350D01*
X44494Y310006D01*
Y303295D01*
X44498Y303290D01*
Y302710D01*
X45620Y301588D01*
X46068D01*
X46119Y301554D01*
G03X48350Y301412I1236J1822D01*
G01X48393Y301434D01*
X49045D01*
X49401Y301790D01*
Y301886D01*
X49814Y302298D01*
X50998D01*
X52069Y303370D01*
X52332D01*
X52631Y303071D01*
X52607Y302964D01*
G03X52568Y302616I1563J-351D01*
G01Y301016D01*
G03X52712Y300353I1602J1D01*
G01X52730Y300314D01*
G37*
G36*
G01X79170Y288011D02*
X78781Y288400D01*
Y289873D01*
X77976Y290678D01*
X64489D01*
X64100Y291067D01*
Y291761D01*
X64242Y291902D01*
Y293976D01*
X64270Y294004D01*
Y296885D01*
X63417Y297738D01*
X56848D01*
X56192Y297082D01*
Y295167D01*
X56191Y295157D01*
G03Y294737I2192J-210D01*
G01X56192Y294727D01*
Y293976D01*
X55929Y293713D01*
X54003D01*
X53804Y293912D01*
Y296772D01*
X53932Y296899D01*
Y303470D01*
X53804Y303597D01*
Y305924D01*
X53702Y306027D01*
Y308101D01*
X53900Y308300D01*
X55866D01*
X59466Y304700D01*
X61710D01*
G03X61890I90J2200D01*
G01X63000D01*
X64000Y305700D01*
Y306810D01*
G03Y306990I-2200J90D01*
G01Y308300D01*
X62450Y309850D01*
Y317900D01*
X66900D01*
X70800Y314000D01*
X73700D01*
X75900Y311800D01*
Y307050D01*
X79960Y302990D01*
Y295210D01*
X80518Y294652D01*
X81548D01*
X81600Y294600D01*
X84100D01*
X84588Y294112D01*
Y288137D01*
X84462Y288011D01*
X79170D01*
G37*
G36*
G01X63040Y293974D02*
Y292400D01*
X61440Y290800D01*
X57600D01*
X56600Y289800D01*
Y287200D01*
X60410Y283390D01*
X81890D01*
X85800Y287300D01*
Y295443D01*
X85438Y295805D01*
X82177D01*
X81510Y296472D01*
Y304290D01*
X81536Y304354D01*
X77500Y308390D01*
Y309037D01*
X77508Y309065D01*
G03Y310335I-2108J635D01*
G01X77500Y310363D01*
Y311900D01*
X70200Y319200D01*
X60400D01*
X59500Y318300D01*
Y310900D01*
X59317Y310717D01*
X59208Y310743D01*
G03X56923Y309900I-507J-2143D01*
G01X53800D01*
X53170Y309270D01*
X53150Y309258D01*
G03X52642Y308750I850J-1358D01*
G01X52630Y308730D01*
X52500Y308600D01*
Y308462D01*
X52489Y308430D01*
G03X52398Y307900I1511J-532D01*
G01Y306300D01*
G03X52489Y305770I1602J2D01*
G01X52500Y305738D01*
Y305500D01*
X51218Y304218D01*
X50570D01*
G03X49795Y304018I0J-1602D01*
G01X48937D01*
X47710Y302790D01*
X46118D01*
X45700Y303208D01*
Y307430D01*
G02X46361Y307733I400J0D01*
G03Y311067I1439J1667D01*
G02X45700Y311370I-261J303D01*
G01Y320600D01*
X48700Y323600D01*
X56600D01*
X56650Y323550D01*
X57600Y324500D01*
X69900D01*
X72231Y322169D01*
X72242Y322107D01*
G03X73858Y320491I1979J363D01*
G01X73920Y320480D01*
X74400Y320000D01*
X85000D01*
X85100Y320100D01*
X90000D01*
Y315036D01*
X87860Y312896D01*
Y298330D01*
X91998Y294192D01*
Y292866D01*
X92031Y292833D01*
Y285269D01*
X77364Y270602D01*
X75011D01*
X74991Y270779D01*
G03X74460Y271800I-1591J-179D01*
G02Y272400I265J300D01*
G03X75002Y273600I-1060J1201D01*
G01Y276200D01*
G03X73400Y277802I-1602J0D01*
G01X70800D01*
G03X69750Y277409I1J-1602D01*
G03X68700Y277802I-1051J-1209D01*
G01X66100D01*
G03X64572Y276680I0J-1601D01*
G01X64528Y276540D01*
X61820D01*
X50190Y288170D01*
Y291893D01*
X50646Y292349D01*
X56649D01*
X57401Y293101D01*
Y296101D01*
X57773Y296473D01*
X62742D01*
X62992Y296223D01*
X62985Y296131D01*
G03X62980Y296007I1597J-126D01*
G01Y294407D01*
G03X63033Y293999I1602J1D01*
G01X63040Y293974D01*
G37*
G36*
G01X103740Y304050D02*
X103340Y304450D01*
Y310050D01*
X103382Y310092D01*
Y310903D01*
G03X103445Y313482I-1752J1333D01*
G01X103410Y313533D01*
Y314169D01*
X104795Y315554D01*
X109200D01*
X110640Y314114D01*
Y305050D01*
X109640Y304050D01*
X103740D01*
G37*
G36*
G01X136405Y617084D02*
X135932Y617557D01*
X135919Y617611D01*
G03X134866Y618663I-1397J-346D01*
G01X134812Y618677D01*
X134519Y618970D01*
X134518D01*
X133988Y619500D01*
X120549D01*
X120519Y619470D01*
X118519Y621470D01*
Y627220D01*
X118769Y627470D01*
X131394D01*
X135269Y623595D01*
X139894D01*
X141769Y625470D01*
X167519D01*
X169769Y623220D01*
Y618970D01*
X167019Y616220D01*
X164456D01*
G02X164086Y616772I0J400D01*
G03X161676I-1205J494D01*
G02X161306Y616220I-370J-152D01*
G01X160519D01*
X159698Y615399D01*
X159624Y615394D01*
G03X158417Y614187I92J-1299D01*
G01X158412Y614113D01*
X158067Y613768D01*
X157865Y613971D01*
X157867Y614057D01*
G03X156071Y615299I-1301J38D01*
G02X155519Y615669I-152J370D01*
G01Y616970D01*
X154441Y618048D01*
G03X154221Y618268I-1024J-804D01*
G01X153019Y619470D01*
X144269D01*
X141882Y617084D01*
X136405D01*
G37*
G36*
G01X113500Y764000D02*
X103000D01*
X102000Y765000D01*
Y779000D01*
X104000Y781000D01*
X113500D01*
X114500Y780000D01*
Y765000D01*
X113500Y764000D01*
G37*
G36*
G01X115500Y874500D02*
Y881500D01*
X115850Y881850D01*
X131650D01*
X132000Y881500D01*
Y881000D01*
X131000Y880000D01*
Y825500D01*
X123500Y818000D01*
X102300D01*
X101000Y819300D01*
Y834900D01*
X108500Y842400D01*
Y867500D01*
X111912Y870912D01*
X111953Y870927D01*
G03X114900Y873874I-1717J4664D01*
G01X114915Y873915D01*
X115500Y874500D01*
G37*
G36*
G01X140174Y500958D02*
G03X139000Y503531I-2574J380D01*
G01Y513000D01*
X141000Y515000D01*
Y523000D01*
X142000Y524000D01*
X146950D01*
G03X147700Y523598I750J499D01*
G01X149300D01*
G03X150050Y524000I0J901D01*
G01X162500D01*
X163500Y523000D01*
Y501500D01*
X162500Y500500D01*
X140570D01*
G02X140174Y500958I0J400D01*
G37*
G36*
G01X147800Y822600D02*
X137400D01*
X135500Y824500D01*
Y878600D01*
X133500Y880600D01*
Y881400D01*
X151000D01*
Y825800D01*
X147800Y822600D01*
G37*
G36*
G01X270500Y138500D02*
X251500D01*
X250000Y140000D01*
Y168000D01*
X254000Y172000D01*
Y191000D01*
X254054Y191054D01*
Y192902D01*
X256803Y195651D01*
X266774D01*
X271000Y191425D01*
Y191331D01*
X272811Y189520D01*
Y184138D01*
X271000Y182327D01*
Y139000D01*
X270500Y138500D01*
G37*
G36*
G01X246500Y154000D02*
X237500D01*
X236500Y155000D01*
Y189000D01*
X237500Y190000D01*
X250000D01*
X250500Y189500D01*
Y175000D01*
X247500Y172000D01*
Y155000D01*
X246500Y154000D01*
G37*
G36*
G01X336927Y711427D02*
X337553Y712054D01*
X385105D01*
X452052Y779000D01*
X478500D01*
X480870Y776630D01*
X480885Y776593D01*
G03X483710Y775365I2040J829D01*
G01X483831Y775411D01*
X485534Y773708D01*
X485761D01*
G03X487206Y772796I1445J689D01*
G01X488204D01*
X488500Y772500D01*
Y771193D01*
G02X488070Y770794I-400J0D01*
G03X485774Y769150I-164J-2196D01*
G01X485735Y769000D01*
X455000D01*
X393500Y707500D01*
X371421D01*
G03X369579I-921J-2000D01*
G01X343500D01*
X310190Y674190D01*
X304810D01*
X304000Y675000D01*
Y678500D01*
X335373Y709873D01*
X335422Y709888D01*
G03X336912Y711378I-622J2112D01*
G01X336927Y711427D01*
G37*
G36*
G01X502025Y834752D02*
X500969Y833697D01*
X500882Y833700D01*
G03X498873Y832551I-74J-2201D01*
G01X491020D01*
X489721Y833850D01*
X475126D01*
X473827Y832551D01*
X455118D01*
G02X442000Y845669I0J13118D01*
G01Y865778D01*
X446996D01*
Y845669D01*
G03X455118Y837547I8122J0D01*
G01X517323D01*
G03X525445Y845669I0J8122D01*
G01Y865400D01*
X530441D01*
Y845669D01*
G02X529045Y839781I-13118J1D01*
G01X527662Y838398D01*
X527575Y838401D01*
G03X525457Y835378I-75J-2201D01*
G02X524597Y834752I-8144J10284D01*
G01X502025D01*
G37*
G36*
G01X769600Y51100D02*
X764532Y46032D01*
G02X763942Y46059I-283J283D01*
G03X760203Y45461I-1692J-1409D01*
G01X760153Y45335D01*
X748944D01*
G03X745056I-1944J-1035D01*
G01X738835D01*
X736178Y47992D01*
Y47995D01*
X733832Y50341D01*
Y54420D01*
X733830Y54422D01*
Y56950D01*
X725585Y65195D01*
X715805D01*
X704540Y76460D01*
Y103130D01*
X630370Y177300D01*
X516500D01*
X502640Y191160D01*
Y196096D01*
X502400Y196336D01*
Y199600D01*
X492700Y209300D01*
Y240200D01*
X502400Y249900D01*
Y293349D01*
X502539Y293393D01*
G03Y297587I-672J2097D01*
G01X502400Y297631D01*
Y298964D01*
X512281Y308845D01*
X537636D01*
X539117Y307364D01*
Y298951D01*
X529741Y289575D01*
X529669Y289568D01*
G03X527689Y287588I212J-2192D01*
G01X527682Y287516D01*
X526185Y286019D01*
X519491D01*
X518119Y284647D01*
Y245100D01*
X537610Y225610D01*
Y221990D01*
X544479Y215121D01*
X544494Y215088D01*
G03X544800Y214603I2000J923D01*
G01Y213031D01*
X546513Y211318D01*
X559129D01*
X577538Y192910D01*
X641190D01*
X716685Y117415D01*
Y78345D01*
X721935Y73095D01*
X732930D01*
X747810Y58215D01*
X762900D01*
X768085Y63400D01*
X769949D01*
G03X774051I2051J800D01*
G01X841100D01*
X841574Y62926D01*
X841649Y63000D01*
X844353D01*
X844517Y62836D01*
X863472D01*
X863636Y63000D01*
X865000D01*
X868322Y66322D01*
X919858D01*
X922696Y69160D01*
X939140D01*
X945700Y62600D01*
X945864D01*
X946180Y62284D01*
X950616D01*
X958714Y54186D01*
X984260D01*
X987108Y51338D01*
Y48255D01*
X988500Y46863D01*
Y43344D01*
X988498Y43342D01*
Y38782D01*
X987268Y37552D01*
X958282D01*
X958280Y37551D01*
X951777D01*
X950500Y38828D01*
Y50000D01*
X946150Y54350D01*
X913350D01*
X911840Y55860D01*
X911824Y55896D01*
G03X910656Y57064I-2027J-859D01*
G01X910620Y57080D01*
X910200Y57500D01*
X876984D01*
X875773Y58711D01*
X870412D01*
X869172Y57471D01*
Y56172D01*
X865092Y52092D01*
X864009D01*
X861186Y49269D01*
X859580D01*
X859564Y49272D01*
G03X858836I-364J-2172D01*
G01X858820Y49269D01*
X858025D01*
X857478Y48722D01*
X855100Y51100D01*
X769600D01*
G37*
G36*
G01X844373Y673814D02*
X525296D01*
X524263Y674847D01*
Y717035D01*
X528396Y721168D01*
X852121D01*
X854360Y718929D01*
Y683801D01*
X844373Y673814D01*
G37*
G36*
G01X562500Y754000D02*
X551500Y765000D01*
X530700D01*
X530500Y765200D01*
Y769800D01*
X530000Y770300D01*
Y775400D01*
X530600Y776000D01*
X531402D01*
G03X531598I98J2600D01*
G01X568000D01*
X582000Y762000D01*
X744000D01*
X791500Y809500D01*
X850500D01*
X854500Y805500D01*
Y797500D01*
X853500Y796500D01*
X808000D01*
X765500Y754000D01*
X562500D01*
G37*
G36*
G01X570563Y246108D02*
X563063D01*
X561563Y247608D01*
Y262608D01*
X562563Y263608D01*
X571063D01*
X572063Y262608D01*
Y247608D01*
X570563Y246108D01*
G37*
G36*
G01X594063Y246238D02*
X592509Y244684D01*
X586593D01*
X586306Y244972D01*
X582102D01*
X582078Y244995D01*
G03X581821Y245523I-1544J-425D01*
G01Y246306D01*
X581019Y247108D01*
X576063D01*
X574563Y248608D01*
Y263108D01*
X566063Y271608D01*
Y312108D01*
X567563Y313608D01*
X589963D01*
X594063Y309508D01*
Y246238D01*
G37*
G36*
G01X555000Y355500D02*
X554500Y356000D01*
Y361500D01*
X555493Y362493D01*
X555587Y362485D01*
G03X555731Y362478I150J1595D01*
G01X557331D01*
G03X557578Y362498I-5J1602D01*
G01X557593Y362500D01*
X559469D01*
X559484Y362498D01*
G03X559731Y362478I252J1582D01*
G01X561331D01*
G03X561578Y362498I-5J1602D01*
G01X561593Y362500D01*
X565000D01*
X565500Y362000D01*
Y356000D01*
X565000Y355500D01*
X555000D01*
G37*
G36*
G01X611563Y230108D02*
X600000D01*
X599908Y230200D01*
X597300D01*
X596100Y231400D01*
Y250637D01*
X597563Y252100D01*
Y298008D01*
X599963Y300408D01*
X607763D01*
X613063Y295108D01*
Y231608D01*
X611563Y230108D01*
G37*
G36*
G01X616000Y337500D02*
X614000Y339500D01*
Y371000D01*
X619000Y376000D01*
X643000D01*
X644500Y374500D01*
Y367000D01*
X643000Y365500D01*
X640578D01*
G03X639800Y365702I-779J-1400D01*
G01X638200D01*
G03X637464Y365522I2J-1602D01*
G01X637421Y365500D01*
X637079D01*
X637036Y365522D01*
G03X636300Y365702I-738J-1422D01*
G01X634700D01*
G03X633964Y365522I2J-1602D01*
G01X633921Y365500D01*
X633580D01*
X632560Y366520D01*
X625031D01*
X624000Y365489D01*
Y355962D01*
X623989Y355930D01*
G03X623898Y355400I1511J-532D01*
G01Y353800D01*
G03X623989Y353270I1602J2D01*
G01X624000Y353238D01*
Y349000D01*
X625500Y347500D01*
X626135D01*
G03X626200Y347498I82J1599D01*
G01X627800D01*
G03X627865Y347500I-17J1601D01*
G01X629635D01*
G03X629700Y347498I82J1599D01*
G01X631300D01*
G03X631365Y347500I-17J1601D01*
G01X634635D01*
G03X634700Y347498I82J1599D01*
G01X636300D01*
G03X636365Y347500I-17J1601D01*
G01X638135D01*
G03X638200Y347498I82J1599D01*
G01X639800D01*
G03X639865Y347500I-17J1601D01*
G01X644000D01*
X645000Y346500D01*
Y338500D01*
X644000Y337500D01*
X616000D01*
G37*
G36*
G01X640500Y350000D02*
X639202Y348702D01*
X625998D01*
X625500Y349199D01*
Y364224D01*
X626493Y365217D01*
X631179D01*
X631896Y364500D01*
X632881D01*
X633082Y364298D01*
X639702D01*
X640500Y363500D01*
Y350000D01*
G37*
G36*
G01X657219Y219324D02*
X656642Y219902D01*
X655356D01*
X654934Y220324D01*
Y236324D01*
X664229Y245619D01*
X696100D01*
X696700Y245019D01*
Y242800D01*
X697150Y242350D01*
X737250D01*
X739000Y240600D01*
Y221700D01*
X736624Y219324D01*
X714745D01*
X714736Y219515D01*
G03X709538I-2599J-123D01*
G01X709529Y219324D01*
X706963D01*
G02X706640Y219960I0J400D01*
G03X702434I-2103J1532D01*
G02X702111Y219324I-323J-236D01*
G01X657219D01*
G37*
G36*
G01X666739Y246961D02*
X665024Y248676D01*
Y275105D01*
X668380Y278461D01*
X699500D01*
X700300Y277661D01*
Y275202D01*
X699798D01*
Y249000D01*
X698400D01*
X696600Y247200D01*
Y246961D01*
X666739D01*
G37*
G36*
G01X683718Y283000D02*
X668800D01*
X668300Y283500D01*
Y302200D01*
X668953Y302853D01*
X684571D01*
X685071Y302353D01*
Y284353D01*
X683718Y283000D01*
G37*
G36*
G01X716337Y193992D02*
X700337D01*
X699837Y194492D01*
Y212992D01*
X701837Y214992D01*
X715737D01*
X716837Y213892D01*
Y194492D01*
X716337Y193992D01*
G37*
G36*
G01X704437Y244284D02*
X702337Y246384D01*
Y247798D01*
X702402D01*
Y275228D01*
X701502Y276128D01*
Y278159D01*
X701465Y278195D01*
Y280666D01*
X701902Y281102D01*
Y282348D01*
X739052D01*
X739254Y282433D01*
X740329Y281358D01*
Y246784D01*
X737829Y244284D01*
X704437D01*
G37*
G36*
G01X928000Y220000D02*
Y222500D01*
X926500Y224000D01*
X925500D01*
X925000Y224500D01*
Y226500D01*
X925500Y227000D01*
X927000D01*
X928000Y228000D01*
Y230100D01*
X926600Y231500D01*
X926242D01*
X926199Y231521D01*
G03X926122Y231557I-611J-1206D01*
G01X926087Y231572D01*
X926058Y231602D01*
X926005D01*
X925977Y231610D01*
G03X925914Y231627I-384J-1297D01*
G01X925860Y231640D01*
X925000Y232500D01*
Y235000D01*
X925346Y235346D01*
X925485Y235245D01*
G03X925900Y235108I416J565D01*
G01X926900D01*
G03X927539Y235521I0J701D01*
G01X927554Y235554D01*
X928000Y236000D01*
Y240500D01*
X926859Y241641D01*
X926891Y241754D01*
G03X926500Y243126I-1300J371D01*
G01Y245061D01*
G03Y247063I-909J1001D01*
G01Y248998D01*
G03Y251000I-909J1001D01*
G01Y252935D01*
G03Y254937I-909J1001D01*
G01Y256872D01*
G03Y258874I-909J1001D01*
G01Y295000D01*
X905000Y316500D01*
X713500D01*
X700700Y303700D01*
Y281600D01*
X700210Y281110D01*
X689950D01*
X686931Y284128D01*
Y315931D01*
X725500Y354500D01*
X906447D01*
G02X906839Y354023I0J-400D01*
G03X911161I2161J-423D01*
G02X911553Y354500I392J77D01*
G01X950000D01*
X968000Y336500D01*
Y258885D01*
G03Y256861I897J-1012D01*
G01Y254948D01*
G03Y252924I897J-1012D01*
G01Y251011D01*
G03Y248987I897J-1012D01*
G01Y247074D01*
G03Y245050I897J-1012D01*
G01Y243137D01*
G03Y241113I897J-1012D01*
G01Y239500D01*
X966500Y238000D01*
Y235700D01*
X966099Y235299D01*
G02X965829Y235287I-142J141D01*
G03X964476Y232989I-869J-1036D01*
G02X964603Y232779I-72J-187D01*
G03X964598Y232700I697J-84D01*
G01Y231900D01*
G03X965300Y231198I702J0D01*
G01X966102D01*
X966500Y230800D01*
Y227800D01*
X966113Y227413D01*
G02X965841Y227403I-141J141D01*
G03X964479Y225114I-881J-1026D01*
G02X964605Y224899I-72J-187D01*
G03X964598Y224800I695J-99D01*
G01Y224000D01*
G03X965300Y223298I702J0D01*
G01X966100D01*
Y223100D01*
X966500Y222700D01*
Y220000D01*
X965000D01*
X964500Y220500D01*
Y222500D01*
X963000Y224000D01*
X959500D01*
X959443Y223943D01*
G02X959102Y224084I-141J141D01*
G01Y224800D01*
G03X959024Y225121I-702J-1D01*
G01X959002Y225164D01*
Y226019D01*
X958421Y226600D01*
X958408Y226658D01*
G03X956583Y225122I-1322J-281D01*
G02X956707Y224906I-74J-186D01*
G03X956698Y224800I692J-112D01*
G01Y224000D01*
G03X957400Y223298I702J0D01*
G01X958449D01*
X958552Y223052D01*
X958500Y223000D01*
Y220000D01*
X957000D01*
X956500Y220500D01*
Y222500D01*
X956452Y222548D01*
Y222708D01*
X955558Y223602D01*
X953843D01*
X953798Y223626D01*
G03X952500I-649J-1186D01*
G01X952455Y223602D01*
X951992D01*
X951891Y223500D01*
X951697D01*
G02X951299Y223936I0J400D01*
G03X951302Y224000I-699J65D01*
G01Y224800D01*
G03X951224Y225121I-702J-1D01*
G01X951202Y225164D01*
Y225945D01*
X950547Y226600D01*
X950534Y226658D01*
G03X948771Y225099I-1322J-281D01*
G02X948904Y224886I-66J-189D01*
G03X948898Y224800I696J-92D01*
G01Y224000D01*
G03X949600Y223298I702J0D01*
G01X950600D01*
G03X950796Y223326I0J702D01*
G01X950909Y223359D01*
X951134Y223134D01*
X950500Y222500D01*
Y220000D01*
X936000D01*
X935652Y220348D01*
Y221958D01*
X935500Y222109D01*
Y222500D01*
X934000Y224000D01*
X932000D01*
X930500Y222500D01*
Y221000D01*
X929500Y220000D01*
X928000D01*
G37*
G36*
G01X738909Y284477D02*
X738508Y284878D01*
X701992D01*
Y298884D01*
X703500Y300392D01*
X738092D01*
X739592Y298892D01*
Y284760D01*
G02X738909Y284477I-400J0D01*
G37*
G36*
G01X985744Y327531D02*
X954405Y358870D01*
X725559D01*
X695253Y328564D01*
X681995D01*
X675702Y334858D01*
Y366012D01*
X675100Y366613D01*
Y403808D01*
X685782Y414490D01*
X1195213D01*
G03X1197987I1387J1710D01*
G01X1244504D01*
X1257958Y401036D01*
Y349718D01*
X1250236Y341996D01*
Y341900D01*
X1235867Y327531D01*
X985744D01*
G37*
G36*
G01X753787Y196442D02*
X753109Y195764D01*
G03X750256Y195672I-1372J-1722D01*
G02X749718I-269J296D01*
G03X746250Y194992I-1481J-1630D01*
G01X721837D01*
X720837Y195992D01*
Y211392D01*
X724144Y214698D01*
X752630D01*
X753787Y213542D01*
Y196442D01*
G37*
G36*
G01X773195Y214800D02*
X768000Y219995D01*
X753153D01*
X750182Y222966D01*
Y276379D01*
X751030Y277227D01*
Y300140D01*
X755176Y304285D01*
X890349D01*
X894138Y300496D01*
Y263173D01*
X893958Y263155D01*
G03Y260465I137J-1345D01*
G01X894138Y260447D01*
Y259236D01*
X893958Y259218D01*
G03Y256528I137J-1345D01*
G01X894138Y256510D01*
Y251362D01*
X893958Y251344D01*
G03Y248654I137J-1345D01*
G01X894138Y248636D01*
Y247425D01*
X893958Y247407D01*
G03X893347Y244936I137J-1345D01*
G02X893408Y244320I-222J-333D01*
G01X891900Y242812D01*
G02X891284Y242873I-283J283D01*
G03X889410Y240999I-1126J-748D01*
G02X889471Y240383I-222J-333D01*
G01X887939Y238851D01*
Y231468D01*
G02X887238Y231205I-400J0D01*
G03Y229423I-1017J-891D01*
G02X887939Y229160I301J-263D01*
G01Y223594D01*
G02X887238Y223331I-400J0D01*
G03Y221549I-1017J-891D01*
G02X887939Y221286I301J-263D01*
G01Y217413D01*
X887336Y216810D01*
X883466D01*
G02X883196Y217505I0J400D01*
G03X881372I-912J998D01*
G02X881102Y216810I-270J-295D01*
G01X879529D01*
G02X879259Y217505I0J400D01*
G03X877435I-912J998D01*
G02X877165Y216810I-270J-295D01*
G01X806000D01*
X803990Y214800D01*
X773195D01*
G37*
G36*
G01X872400Y122500D02*
X871900Y123000D01*
Y164600D01*
X872500Y165200D01*
X891100D01*
X892000Y164300D01*
Y162300D01*
X892300Y162000D01*
X893091D01*
X893092Y161998D01*
X895802D01*
X896000Y161800D01*
Y123900D01*
X894600Y122500D01*
X891509D01*
G02X891200Y123155I-1J400D01*
G03X889116I-1042J861D01*
G02X888807Y122500I-308J-255D01*
G01X883637D01*
G02X883332Y123158I0J400D01*
G03X881268I-1032J874D01*
G02X880963Y122500I-305J-258D01*
G01X875761D01*
G02X875452Y123155I-1J400D01*
G03X873368I-1042J861D01*
G02X873059Y122500I-308J-255D01*
G01X872400D01*
G37*
G36*
G01X996748Y820866D02*
Y650669D01*
G02X983748Y637669I-13000J0D01*
G01X926819D01*
G02X913819Y650669I0J13000D01*
G01Y820866D01*
G03X902134Y832551I-11685J0D01*
G01X872441D01*
G02X867723Y833429I1J13118D01*
G01X860201Y840951D01*
G02X859323Y845669I12240J4719D01*
G01Y865500D01*
X864319D01*
Y845669D01*
G03X872441Y837547I8122J0D01*
G01X902134D01*
G02X918815Y820866I0J-16681D01*
G01Y650669D01*
G03X926819Y642665I8004J0D01*
G01X983748D01*
G03X991752Y650669I0J8004D01*
G01Y820866D01*
G02X1008433Y837547I16681J0D01*
G01X1013386D01*
G03X1021508Y845669I0J8122D01*
G01Y866301D01*
X1026504D01*
Y845669D01*
G02X1013386Y832551I-13118J0D01*
G01X1008433D01*
G03X996748Y820866I0J-11685D01*
G37*
G36*
G01X896700Y129400D02*
Y162200D01*
X896400Y162500D01*
X896028D01*
X896000Y162508D01*
G03X895800Y162538I-203J-672D01*
G01X894800D01*
G03X894600Y162508I3J-702D01*
G01X894572Y162500D01*
X893300D01*
X893000Y162800D01*
Y165500D01*
X893300Y165800D01*
X895300D01*
X895700Y166200D01*
Y183300D01*
X895282Y183718D01*
G03X894764Y184246I-1187J-647D01*
G01X894741Y184259D01*
X891700Y187300D01*
Y235157D01*
X891789Y235216D01*
G03X892098Y235734I-389J583D01*
G01X892105Y235805D01*
X892500Y236200D01*
Y237200D01*
X895300Y240000D01*
X924200D01*
X924500Y239700D01*
Y238987D01*
G03X924447Y237467I1091J-799D01*
G01X924532Y237332D01*
X924200Y237000D01*
X902600D01*
X902200Y237400D01*
X900100D01*
X899700Y237000D01*
Y207901D01*
G02X899011Y207625I-400J0D01*
G03Y205759I-979J-933D01*
G02X899700Y205483I289J-276D01*
G01Y188200D01*
X901900Y186000D01*
X904400D01*
X904800Y185600D01*
Y184800D01*
X905400Y184200D01*
X905433D01*
X905477Y184177D01*
G03X905800Y184098I324J623D01*
G01X906702D01*
X906800Y184000D01*
Y182400D01*
X906700Y182300D01*
X900100D01*
X899700Y181900D01*
Y167500D01*
X901200Y166000D01*
X901690D01*
X901709Y165996D01*
G03X902229I260J1327D01*
G01X902248Y166000D01*
X905500D01*
X905800Y165700D01*
Y164700D01*
X906700Y163800D01*
Y163100D01*
X906200Y162600D01*
X902800D01*
X902770Y162570D01*
X902368D01*
G03X902098Y162515I2J-702D01*
G01X902061Y162500D01*
X901700D01*
X901300Y162100D01*
Y160624D01*
G03X900779Y160091I669J-1175D01*
G01X900765Y160065D01*
X900700Y160000D01*
Y159917D01*
X900689Y159885D01*
G03Y159013I1280J-436D01*
G01X900700Y158981D01*
Y155980D01*
X900689Y155948D01*
G03Y155076I1280J-436D01*
G01X900700Y155044D01*
Y152043D01*
X900689Y152011D01*
G03Y151139I1280J-436D01*
G01X900700Y151107D01*
Y148106D01*
X900689Y148074D01*
G03Y147202I1280J-436D01*
G01X900700Y147170D01*
Y144169D01*
X900689Y144137D01*
G03Y143265I1280J-436D01*
G01X900700Y143233D01*
Y140232D01*
X900689Y140200D01*
G03Y139328I1280J-436D01*
G01X900700Y139296D01*
Y136295D01*
X900689Y136263D01*
G03Y135391I1280J-436D01*
G01X900700Y135359D01*
Y132358D01*
X900689Y132326D01*
G03Y131454I1280J-436D01*
G01X900700Y131422D01*
Y131000D01*
X899100Y129400D01*
X896700D01*
G37*
G36*
G01X920000Y182200D02*
X942400Y159800D01*
Y157300D01*
X942050Y156950D01*
X939900D01*
X939850Y157000D01*
Y159650D01*
X933804Y165696D01*
X933801Y165773D01*
G03X933135Y166439I-701J-35D01*
G01X933058Y166442D01*
X925670Y173830D01*
X925655Y173870D01*
G03X925252Y174273I-655J-252D01*
G01X925212Y174288D01*
X922450Y177050D01*
X921250D01*
X920000Y175800D01*
Y173850D01*
X926350Y167500D01*
Y166638D01*
G02X926161Y166438I-200J0D01*
G03X925498Y165738I38J-700D01*
G01Y165348D01*
X924150Y164000D01*
X924048Y164017D01*
G03X921218Y162450I-428J-2567D01*
G01X919385D01*
G02X919004Y162972I0J400D01*
G03X916479Y163929I-1287J413D01*
G03X913401Y162450I-689J-2509D01*
G01X909600D01*
X907200Y164850D01*
X906750D01*
X906400Y165200D01*
Y165900D01*
X905800Y166500D01*
X905709D01*
X905708Y166502D01*
X901408D01*
X900600Y167309D01*
Y181600D01*
X907100D01*
X907500Y182000D01*
Y184400D01*
X907200Y184700D01*
X906809D01*
X906808Y184702D01*
X905798D01*
X905600Y184900D01*
Y186100D01*
X904900Y186800D01*
X901809D01*
X900600Y188009D01*
Y236600D01*
X900850Y236850D01*
X901775D01*
G03X901804Y236846I199J1337D01*
G01X902250Y236400D01*
X923950D01*
X924450Y235900D01*
Y234976D01*
G03Y233526I1141J-725D01*
G01Y231250D01*
X924600Y231100D01*
X925850D01*
X926950Y230000D01*
Y227950D01*
X926700Y227700D01*
X925870D01*
X925851Y227704D01*
G03X925331I-260J-1327D01*
G01X925312Y227700D01*
X925200D01*
X925159Y227659D01*
X925118Y227644D01*
G03X924450Y225652I473J-1267D01*
G01Y223550D01*
X924700Y223300D01*
X925860D01*
G03X925900Y223298I55J699D01*
G01X926402D01*
X927100Y222600D01*
Y219650D01*
X927400Y219350D01*
X930350D01*
X931450Y220450D01*
Y222400D01*
X932300Y223250D01*
X933650D01*
X935150Y221750D01*
Y219550D01*
X935250Y219450D01*
X935789D01*
X935826Y219434D01*
G03X936100Y219378I275J646D01*
G01X937100D01*
G03X937374Y219434I-1J702D01*
G01X937411Y219450D01*
X943450D01*
X943600Y219300D01*
X951350D01*
X951650Y219600D01*
Y222550D01*
X952200Y223100D01*
X955350D01*
X955755Y222695D01*
X955743Y222599D01*
G03X955950Y221707I1343J-158D01*
G01Y219950D01*
X956600Y219300D01*
X959000D01*
X959300Y219600D01*
Y222650D01*
X959948Y223298D01*
X960600D01*
G03X960923Y223377I-1J702D01*
G01X960967Y223400D01*
X962850D01*
X963600Y222650D01*
Y219800D01*
X964100Y219300D01*
X966800D01*
X967300Y219800D01*
Y222200D01*
X968250Y223150D01*
X969200D01*
X969650Y223600D01*
Y225254D01*
G03X968637Y227704I-753J1123D01*
G01X968618Y227700D01*
X967550D01*
X967350Y227900D01*
Y230550D01*
X967950Y231150D01*
X969850D01*
X970250Y231550D01*
Y235850D01*
X970600Y236200D01*
X987550D01*
X988100Y236750D01*
X993800D01*
X994000Y236550D01*
Y207909D01*
X993998Y207908D01*
Y205292D01*
X994000Y205291D01*
Y187400D01*
X993502Y186902D01*
X989992D01*
X989991Y186900D01*
X989500D01*
X989000Y186400D01*
Y184800D01*
X988800Y184600D01*
X987600D01*
X987200Y184200D01*
Y182200D01*
X987600Y181800D01*
X987891D01*
X987892Y181798D01*
X988124D01*
X988155Y181788D01*
G03X989009I427J1283D01*
G01X989040Y181798D01*
X992061D01*
X992092Y181788D01*
G03X992946I427J1283D01*
G01X992977Y181798D01*
X993802D01*
X994000Y181600D01*
Y167300D01*
X993500Y166800D01*
X990300D01*
X990000Y166500D01*
Y165000D01*
X989800Y164800D01*
X987600D01*
X987100Y164300D01*
Y164009D01*
X987098Y164008D01*
Y162592D01*
X987100Y162591D01*
Y162300D01*
X987500Y161900D01*
X994000D01*
Y156950D01*
X993350Y156300D01*
X992785D01*
X992744Y156320D01*
G03X990432Y156300I-1136J-2341D01*
G01X986400D01*
X985950Y156750D01*
Y157750D01*
X984835Y158865D01*
X984823Y158884D01*
G03X984036Y159671I-2191J-1404D01*
G01X984017Y159683D01*
X981350Y162350D01*
X981169D01*
G03X978412Y163998I-2429J-933D01*
G01X978314Y163986D01*
X975900Y166400D01*
X975859D01*
X957650Y184609D01*
Y185100D01*
X957302Y185448D01*
Y185568D01*
G03X956600Y186270I-702J0D01*
G01X956480D01*
X955100Y187650D01*
Y190750D01*
X954852Y190998D01*
Y191258D01*
X953858Y192252D01*
X953494D01*
X953470Y192257D01*
G03X952828I-321J-1313D01*
G01X952804Y192252D01*
X950058D01*
X949750Y192559D01*
Y193150D01*
X950300Y193700D01*
Y194041D01*
X950502Y194242D01*
Y194474D01*
X950510Y194501D01*
G03Y195261I-1298J380D01*
G01X950502Y195288D01*
Y195608D01*
X949683Y196426D01*
X945883D01*
X928150Y214159D01*
Y214200D01*
X926450Y215900D01*
X926409D01*
X926308Y216002D01*
X925092D01*
X924991Y215900D01*
X924750D01*
X924100Y215250D01*
Y215009D01*
X924048Y214958D01*
Y214042D01*
X925498Y212592D01*
Y212200D01*
G03X926200Y211498I702J0D01*
G01X926592D01*
X933598Y204492D01*
Y204300D01*
G03X934300Y203598I702J0D01*
G01X934492D01*
X964998Y173092D01*
Y172818D01*
G03X965700Y172116I702J0D01*
G01X965974D01*
X972798Y165292D01*
Y164938D01*
G03X973500Y164236I702J0D01*
G01X973750D01*
Y163300D01*
X973478Y163028D01*
G02X972885Y163059I-283J283D01*
G03X970642Y164009I-2018J-1642D01*
G01X970549Y164001D01*
X949302Y185248D01*
Y185568D01*
G03X948600Y186270I-702J0D01*
G01X948280D01*
X941702Y192848D01*
Y193300D01*
G03X941000Y194002I-702J0D01*
G01X940548D01*
X923200Y211350D01*
X923159D01*
X922408Y212102D01*
X921192D01*
X921141Y212050D01*
X920750D01*
X920200Y211500D01*
Y211109D01*
X920148Y211058D01*
Y210142D01*
X920200Y210091D01*
Y210050D01*
X925498Y204752D01*
Y204300D01*
G03X926200Y203598I702J0D01*
G01X926652D01*
X957098Y173152D01*
Y172818D01*
G03X957800Y172116I702J0D01*
G01X958134D01*
X964998Y165252D01*
Y164938D01*
G03X965700Y164236I702J0D01*
G01X966014D01*
X967200Y163050D01*
Y161000D01*
X967000Y160800D01*
X965600D01*
X965550Y160850D01*
Y161850D01*
X964750Y162650D01*
X964000D01*
X941702Y184948D01*
Y185568D01*
G03X941000Y186270I-702J0D01*
G01X940380D01*
X933802Y192848D01*
Y193300D01*
G03X933100Y194002I-702J0D01*
G01X932648D01*
X918400Y208250D01*
X916950D01*
X916100Y207400D01*
Y207209D01*
X916048Y207158D01*
Y206242D01*
X916100Y206191D01*
Y206050D01*
X935900Y186250D01*
Y182850D01*
X936126Y182624D01*
G03X936148Y182564I1280J435D01*
G01Y182492D01*
X936213Y182428D01*
G03X936736Y181894I1190J642D01*
G01X936760Y181881D01*
X940149Y178492D01*
X940162Y178468D01*
G03X940673Y177957I1177J666D01*
G01X940697Y177944D01*
X940992Y177648D01*
X941101D01*
X941200Y177550D01*
X944450D01*
X949098Y172902D01*
Y172818D01*
G03X949800Y172116I702J0D01*
G01X949884D01*
X957096Y164904D01*
X957106Y164838D01*
G03X957762Y164238I694J100D01*
G01X957800Y164200D01*
Y163696D01*
G03X956737Y162600I1254J-2280D01*
G01X955900D01*
X946275Y172225D01*
X943325D01*
X941637Y173913D01*
X941623Y173940D01*
G03X941322Y174241I-623J-322D01*
G01X941295Y174255D01*
X941050Y174500D01*
X940559D01*
X932702Y182358D01*
Y183152D01*
X933800Y184250D01*
Y184728D01*
G03X933802Y184768I-699J55D01*
G01Y185568D01*
G03X933100Y186270I-702J0D01*
G01X932730D01*
X925705Y193295D01*
X925698Y193366D01*
G03X925066Y193998I-698J-66D01*
G01X924995Y194005D01*
X918550Y200450D01*
X917250D01*
X916100Y199300D01*
Y197800D01*
X925250Y188650D01*
Y184650D01*
X942300Y167600D01*
X946500D01*
X949097Y165003D01*
X949099Y164923D01*
G03X949785Y164237I701J15D01*
G01X949865Y164235D01*
X953180Y160920D01*
X953195Y160871D01*
G03X953671Y160395I673J197D01*
G01X953720Y160380D01*
X953900Y160200D01*
Y159050D01*
X952900Y158050D01*
Y157150D01*
X952750Y157000D01*
X950400D01*
X949771Y157629D01*
G02X949861Y158263I282J283D01*
G03X948163Y160302I-649J1186D01*
G01X947164D01*
X947121Y160324D01*
G03X947075Y160345I-314J-627D01*
G01X947040Y160360D01*
X941704Y165696D01*
X941701Y165773D01*
G03X941035Y166439I-701J-35D01*
G01X940958Y166442D01*
X933805Y173595D01*
X933800Y173669D01*
G03X933151Y174318I-700J-51D01*
G01X933077Y174323D01*
X922850Y184550D01*
X922309D01*
X922208Y184652D01*
X920992D01*
X920891Y184550D01*
X920750D01*
X920000Y183800D01*
Y183659D01*
X919948Y183608D01*
Y182692D01*
X920000Y182641D01*
Y182200D01*
G37*
G36*
G01X924500Y264000D02*
X908000D01*
X907000Y265000D01*
Y285500D01*
X908000Y286500D01*
X923500D01*
X925000Y285000D01*
Y264500D01*
X924500Y264000D01*
G37*
G36*
G01X922500Y38000D02*
X921000Y39500D01*
Y39870D01*
X921013Y39904D01*
G03Y41456I-2061J776D01*
G01X921000Y41490D01*
Y51000D01*
X922000Y52000D01*
X946500D01*
X947500Y51000D01*
Y39500D01*
X946000Y38000D01*
X922500D01*
G37*
G36*
G01X950000Y164850D02*
X949302Y165548D01*
Y165738D01*
G03X948600Y166440I-702J0D01*
G01X948410D01*
X946700Y168150D01*
X943100D01*
X926175Y185075D01*
Y189025D01*
X916650Y198550D01*
Y199050D01*
X917400Y199800D01*
X918200D01*
X925495Y192505D01*
X925502Y192434D01*
G03X926134Y191802I698J66D01*
G01X926205Y191795D01*
X933100Y184900D01*
Y184500D01*
X932900Y184300D01*
X932870Y184285D01*
G03X932251Y183666I595J-1214D01*
G01X932236Y183636D01*
X932200Y183600D01*
Y183549D01*
X932189Y183517D01*
G03Y182625I1276J-446D01*
G01X932200Y182593D01*
Y182150D01*
X940500Y173850D01*
X940900D01*
X941200Y173550D01*
Y172850D01*
X941607Y172443D01*
X941617Y172427D01*
G03X941809Y172235I583J391D01*
G01X941825Y172225D01*
X942550Y171500D01*
X946100D01*
X951150Y166450D01*
Y165400D01*
X950600Y164850D01*
X950000D01*
G37*
G36*
G01X941300Y162050D02*
X920450Y182900D01*
Y183400D01*
X921200Y184150D01*
X922000D01*
X933707Y172443D01*
X933717Y172427D01*
G03X933909Y172235I583J391D01*
G01X933925Y172225D01*
X941661Y164489D01*
X941666Y164483D01*
G03X941745Y164404I534J455D01*
G01X941751Y164399D01*
X942650Y163500D01*
Y163050D01*
X941650Y162050D01*
X941300D01*
G37*
G36*
G01X933400Y162100D02*
X920550Y174950D01*
Y175450D01*
X921300Y176200D01*
X922150D01*
X925495Y172855D01*
X925500Y172778D01*
G03X926160Y172118I700J40D01*
G01X926237Y172113D01*
X933633Y164717D01*
X933648Y164679D01*
G03X934041Y164286I652J259D01*
G01X934079Y164271D01*
X934775Y163575D01*
Y163125D01*
X933750Y162100D01*
X933400D01*
G37*
G36*
G01X926100Y215500D02*
X945675Y195925D01*
X949475D01*
X950000Y195400D01*
Y194450D01*
X949469Y193919D01*
X949447Y193906D01*
G03X949098Y193300I352J-606D01*
G01Y192500D01*
G03X949734Y191802I701J0D01*
G01X949805Y191795D01*
X949850Y191750D01*
X953650D01*
X954350Y191050D01*
Y187200D01*
X977500Y164050D01*
Y163707D01*
X977403Y163649D01*
G03X976477Y162701I1337J-2232D01*
G01X976420Y162600D01*
X976200D01*
X973002Y165798D01*
X972991Y165860D01*
G03X972422Y166429I-691J-122D01*
G01X972360Y166440D01*
X965205Y173595D01*
X965200Y173669D01*
G03X964551Y174318I-700J-51D01*
G01X964477Y174323D01*
X933802Y204998D01*
Y205100D01*
G03X933100Y205802I-702J0D01*
G01X932998D01*
X925696Y213104D01*
X925683Y213159D01*
G03X925159Y213683I-683J-159D01*
G01X925104Y213696D01*
X924550Y214250D01*
Y214750D01*
X925300Y215500D01*
X926100D01*
G37*
G36*
G01X949674Y184076D02*
X969525Y164225D01*
G02X969459Y163606I-283J-283D01*
G03X968742Y162920I1407J-2189D01*
G02X968132Y162868I-327J231D01*
G01X965202Y165798D01*
X965191Y165860D01*
G03X964622Y166429I-691J-122D01*
G01X964560Y166440D01*
X957299Y173701D01*
X957287Y173760D01*
G03X956742Y174305I-687J-142D01*
G01X956683Y174317D01*
X925660Y205340D01*
X925645Y205375D01*
G03X925275Y205745I-645J-275D01*
G01X925240Y205760D01*
X920650Y210350D01*
Y210850D01*
X921400Y211600D01*
X922200D01*
X941540Y192260D01*
X941555Y192225D01*
G03X941925Y191855I645J275D01*
G01X941960Y191840D01*
X946050Y187750D01*
Y187700D01*
X949108Y184642D01*
X949121Y184590D01*
G03X949622Y184089I679J178D01*
G01X949674Y184076D01*
G37*
G36*
G01X961190Y162905D02*
G03X959063Y164019I-2135J-1488D01*
G01X958981D01*
X957304Y165696D01*
X957301Y165773D01*
G03X956635Y166439I-701J-35D01*
G01X956558Y166442D01*
X949299Y173701D01*
X949287Y173760D01*
G03X948742Y174305I-687J-142D01*
G01X948683Y174317D01*
X944850Y178150D01*
X941200D01*
X936650Y182700D01*
Y186350D01*
X916550Y206450D01*
Y206950D01*
X917300Y207700D01*
X918100D01*
X941950Y183850D01*
Y183800D01*
X962200Y163550D01*
Y163250D01*
X961801Y162851D01*
G02X961190Y162905I-283J283D01*
G37*
G36*
G01X981648Y3406D02*
X965900D01*
Y16280D01*
X981648D01*
Y3406D01*
G37*
G36*
G01X996572Y129300D02*
X996564Y129301D01*
G03X996487Y129305I-109J-1348D01*
G02X996292Y129505I5J200D01*
G01Y141299D01*
X994075Y143516D01*
X993784D01*
X993241Y144059D01*
X993350Y144198D01*
G03X992900Y147852I-2050J1602D01*
G01Y151720D01*
G03X993966Y155080I-1292J2259D01*
G01X993907Y155207D01*
X994800Y156100D01*
Y162000D01*
X994300Y162500D01*
X993940D01*
G03X993900Y162502I-55J-699D01*
G01X992900D01*
G03X992860Y162500I15J-701D01*
G01X987900D01*
X987600Y162800D01*
Y163800D01*
X988000Y164200D01*
X990200D01*
X990700Y164700D01*
Y165900D01*
X990800Y166000D01*
X992240D01*
X992259Y165996D01*
G03X992779I260J1327D01*
G01X992798Y166000D01*
X994200D01*
X994800Y166600D01*
Y181600D01*
X994100Y182300D01*
X988100D01*
X987800Y182600D01*
Y183800D01*
X988000Y184000D01*
X989100D01*
X989700Y184600D01*
Y185900D01*
X990200Y186400D01*
X994000D01*
X994800Y187200D01*
Y205200D01*
X994500Y205500D01*
Y207700D01*
X994800Y208000D01*
Y236800D01*
X994300Y237300D01*
X993940D01*
G03X993900Y237302I-55J-699D01*
G01X992900D01*
G03X992860Y237300I15J-701D01*
G01X987800D01*
X987300Y236800D01*
X970400D01*
X970200Y237000D01*
Y237826D01*
X970206Y237851D01*
G03Y238525I-1309J337D01*
G01X970200Y238550D01*
Y241763D01*
X970206Y241788D01*
G03Y242462I-1309J337D01*
G01X970200Y242487D01*
Y245700D01*
X970206Y245725D01*
G03Y246399I-1309J337D01*
G01X970200Y246424D01*
Y247000D01*
X972000Y248800D01*
X972208D01*
X972249Y248780D01*
G03X973419I585J1219D01*
G01X973460Y248800D01*
X976145D01*
X976186Y248780D01*
G03X977356I585J1219D01*
G01X977397Y248800D01*
X980082D01*
X980123Y248780D01*
G03X981293I585J1219D01*
G01X981334Y248800D01*
X984019D01*
X984060Y248780D01*
G03X985230I585J1219D01*
G01X985271Y248800D01*
X987956D01*
X987997Y248780D01*
G03X989167I585J1219D01*
G01X989208Y248800D01*
X991893D01*
X991934Y248780D01*
G03X993104I585J1219D01*
G01X993145Y248800D01*
X995830D01*
X995871Y248780D01*
G03X997041I585J1219D01*
G01X997082Y248800D01*
X999767D01*
X999808Y248780D01*
G03X1000978I585J1219D01*
G01X1001019Y248800D01*
X1003704D01*
X1003745Y248780D01*
G03X1004915I585J1219D01*
G01X1004956Y248800D01*
X1007641D01*
X1007682Y248780D01*
G03X1008852I585J1219D01*
G01X1008893Y248800D01*
X1011578D01*
X1011619Y248780D01*
G03X1011746Y248727I584J1220D01*
G01X1011788Y248712D01*
X1012405Y248095D01*
G02X1012141Y247413I-283J-283D01*
G03X1013555Y245999I63J-1351D01*
G02X1014237Y246263I399J-19D01*
G01X1014854Y245646D01*
X1014869Y245604D01*
G03X1015300Y245003I1272J457D01*
G01Y243184D01*
G03Y241066I841J-1059D01*
G01Y239247D01*
G03Y237129I841J-1059D01*
G01Y235310D01*
G03Y233192I841J-1059D01*
G01Y231373D01*
G03Y229255I841J-1059D01*
G01Y227436D01*
G03Y225318I841J-1059D01*
G01Y223499D01*
G03Y221381I841J-1059D01*
G01Y219562D01*
G03Y217444I841J-1059D01*
G01Y215625D01*
G03Y213507I841J-1059D01*
G01Y211688D01*
G03Y209570I841J-1059D01*
G01Y207751D01*
G03Y205633I841J-1059D01*
G01Y203814D01*
G03Y201696I841J-1059D01*
G01Y199877D01*
G03Y197759I841J-1059D01*
G01Y195940D01*
G03Y193822I841J-1059D01*
G01Y192003D01*
G03Y189885I841J-1059D01*
G01Y184130D01*
G03Y182012I841J-1059D01*
G01Y180193D01*
G03Y178075I841J-1059D01*
G01Y176256D01*
G03Y174138I841J-1059D01*
G01Y172319D01*
G03Y170201I841J-1059D01*
G01Y168382D01*
G03Y166264I841J-1059D01*
G01Y164445D01*
G03Y162327I841J-1059D01*
G01Y160508D01*
G03Y158390I841J-1059D01*
G01Y156571D01*
G03Y154453I841J-1059D01*
G01Y152634D01*
G03Y150516I841J-1059D01*
G01Y148697D01*
G03Y146579I841J-1059D01*
G01Y144760D01*
G03Y142642I841J-1059D01*
G01Y140823D01*
G03Y138705I841J-1059D01*
G01Y136886D01*
G03Y134768I841J-1059D01*
G01Y132949D01*
G03X1015234Y130887I841J-1059D01*
G01X1015300Y130828D01*
Y130500D01*
X1014200Y129400D01*
X1002100D01*
X1000400Y131100D01*
X998900D01*
X998760Y130960D01*
X998725Y130945D01*
G03X998298Y130300I274J-645D01*
G01Y129499D01*
X998100Y129300D01*
X996572D01*
G37*
G36*
G01X983500Y264500D02*
X971000D01*
X970000Y265500D01*
Y286500D01*
X970500Y287000D01*
X982000D01*
X984500Y284500D01*
Y265500D01*
X983500Y264500D01*
G37*
G36*
G01X1038092Y616474D02*
X1031378Y623188D01*
Y821100D01*
X1033678Y823400D01*
X1157200D01*
X1157300Y823500D01*
X1165506D01*
Y821710D01*
G03X1166740Y820151I1602J0D01*
G01X1166894Y820115D01*
Y778337D01*
X1275720Y669511D01*
Y632315D01*
X1259879Y616474D01*
X1038092D01*
G37*
G36*
G01X1263837Y145078D02*
X1265252D01*
X1265274Y145073D01*
G03X1265632Y145032I360J1561D01*
G01X1267232D01*
G03X1267590Y145073I-2J1602D01*
G01X1267612Y145078D01*
X1268654D01*
X1268676Y145073D01*
G03X1269034Y145032I360J1561D01*
G01X1270634D01*
G03X1270992Y145073I-2J1602D01*
G01X1271014Y145078D01*
X1276832D01*
X1295178Y126732D01*
Y115904D01*
X1292423Y113149D01*
X1120574D01*
X1105684Y98258D01*
X1103991D01*
X1092707Y86975D01*
X1071842D01*
X1068570Y90247D01*
Y283105D01*
X1084412Y298947D01*
X1151309D01*
X1157078Y293178D01*
Y198041D01*
X1166721Y188398D01*
X1267943D01*
X1273262Y183079D01*
Y155354D01*
X1271650Y153742D01*
X1261908D01*
X1261897Y153730D01*
X1261745D01*
X1261744Y153731D01*
X1260264Y152251D01*
Y151914D01*
X1260256Y151906D01*
Y148790D01*
X1260274Y148772D01*
Y147782D01*
X1258744D01*
G03X1258743Y143758I0J-2012D01*
G01X1261944D01*
G03X1263785Y144959I0J2012D01*
G01X1263837Y145078D01*
G37*
G36*
G01X1262500Y192000D02*
X1218200D01*
X1206900Y203300D01*
X1169200D01*
X1164500Y208000D01*
Y217000D01*
X1165400Y217900D01*
X1263100D01*
X1265000Y216000D01*
Y194500D01*
X1262500Y192000D01*
G37*
G36*
G01X1164000Y220000D02*
X1162500Y221500D01*
Y266500D01*
X1164000Y268000D01*
X1219000D01*
X1219198Y267802D01*
Y220698D01*
X1218500Y220000D01*
X1164000D01*
G37*
G36*
G01X1263000Y271500D02*
X1165000D01*
X1163500Y273000D01*
Y296500D01*
X1164500Y297500D01*
X1263000D01*
X1265000Y295500D01*
Y273500D01*
X1263000Y271500D01*
G37*
G36*
G01X1223000Y220000D02*
X1221802Y221198D01*
Y268302D01*
X1222000Y268500D01*
X1264700D01*
X1265600Y267600D01*
Y221000D01*
X1264600Y220000D01*
X1223000D01*
G37*
G36*
G01X1277098Y687934D02*
X1218706Y746326D01*
Y822444D01*
X1219863Y823600D01*
X1324800D01*
X1326100Y822300D01*
Y792300D01*
X1337900Y780500D01*
Y754592D01*
X1330554Y747246D01*
Y743654D01*
X1326837Y739937D01*
X1293457D01*
X1287430Y733910D01*
Y690689D01*
X1284675Y687934D01*
X1277098D01*
G37*
G36*
G01X1263887Y146311D02*
X1263839Y146444D01*
G03X1261944Y147782I-1895J-673D01*
G01X1261586D01*
Y151720D01*
X1262406Y152540D01*
X1265519D01*
G03X1265632Y152536I113J1597D01*
G01X1267232D01*
G03X1267345Y152540I0J1601D01*
G01X1268921D01*
G03X1269034Y152536I113J1597D01*
G01X1270634D01*
G03X1270747Y152540I0J1601D01*
G01X1278780D01*
X1280635Y150685D01*
Y147858D01*
X1279088Y146311D01*
X1263887D01*
G37*
G36*
G01X1354500Y189500D02*
X1346000D01*
X1343500Y192000D01*
Y251000D01*
X1344500Y252000D01*
X1349500D01*
X1350500Y251000D01*
X1364000D01*
X1364500Y250500D01*
Y245000D01*
X1362000Y242500D01*
Y197000D01*
X1354500Y189500D01*
G37*
G36*
G01X1344000Y254500D02*
X1340500Y251000D01*
Y234765D01*
X1339537Y233802D01*
X1328698D01*
X1326145Y236355D01*
Y248080D01*
G03X1326602Y249200I-1144J1120D01*
G01Y250800D01*
G03X1326145Y251920I-1601J0D01*
G01Y273520D01*
X1327125Y274500D01*
X1343500D01*
X1344000Y274000D01*
Y254500D01*
G37*
G36*
G01X1366000Y209000D02*
X1364000Y211000D01*
Y242000D01*
X1367500Y245500D01*
Y250000D01*
X1368500Y251000D01*
X1375500D01*
X1377998Y248502D01*
Y210498D01*
X1376500Y209000D01*
X1366000D01*
G37*
%LPC*%
G75*
G36*
G01X365945Y76624D02*
G02X370914Y71654I-1J-4970D01*
G01Y40157D01*
G02X365945Y35188I-4969J0D01*
G01X356102D01*
G02X351132Y40157I0J4970D01*
G01Y71654D01*
G02X356102Y76624I4970J0D01*
G01X365945D01*
G37*
G36*
G01X19991Y730170D02*
G03X19961Y730833I-238J321D01*
G02X22417Y730943I1146J1880D01*
G03X22447Y730280I238J-321D01*
G02X19991Y730170I-1146J-1880D01*
G37*
G36*
G01X241772Y602494D02*
G03X241758Y601921I272J-293D01*
G02X238128Y602006I-1859J-1821D01*
G03X238142Y602579I-272J293D01*
G02X238141Y606220I1858J1821D01*
G03Y606780I-286J280D01*
G02X241859I1859J1820D01*
G03Y606220I286J-280D01*
G02X241772Y602494I-1859J-1821D01*
G37*
G36*
G01X263000Y586198D02*
G02X262000Y586549I1J1602D01*
G02X261000Y586198I-1001J1251D01*
G01X259600D01*
G02X258179Y587060I0J1602D01*
G01X255804D01*
X254385Y588479D01*
X254265Y588435D01*
G02X255156Y591952I-765J2065D01*
G03X255757I301J263D01*
G02X257421Y592702I1656J-1452D01*
G01X257504D01*
X257998Y593196D01*
Y593700D01*
G02X259600Y595302I1602J0D01*
G01X261000D01*
G02X262000Y594951I-1J-1602D01*
G02X263000Y595302I1001J-1251D01*
G01X264400D01*
G02X265821Y594440I0J-1602D01*
G01X267539D01*
G02X270647Y594933I1795J-1275D01*
G03X271185Y594989I238J321D01*
G02X271279Y591441I1949J-1724D01*
G03X270739Y591468I-285J-281D01*
G02X270502Y591297I-1404J1697D01*
G03X270450Y590657I212J-339D01*
G02X270440Y587334I-1450J-1657D01*
G01Y586019D01*
X270092Y585672D01*
X270109Y585571D01*
G02X264938Y585190I-2569J-415D01*
G01X264939Y585275D01*
X264016Y586198D01*
X263000D01*
G37*
G36*
G01X284350Y580389D02*
G03X284377Y581056I-207J342D01*
G02X284345Y585251I1523J2109D01*
G03X284306Y585918I-239J321D01*
G02X287721Y589688I1300J2254D01*
G01X287781Y589604D01*
X288166D01*
X288226Y589668D01*
G02X291139Y589940I1610J-1503D01*
G01X292179D01*
G02X293600Y590802I1421J-740D01*
G01X295000D01*
G02X295119Y590797I-8J-1602D01*
G03X295548Y591196I29J399D01*
G01Y592750D01*
G02X299952I2202J0D01*
G01Y589598D01*
X299957Y589575D01*
G02X300002Y589200I-1557J-377D01*
G01Y587800D01*
G02X299957Y587425I-1602J2D01*
G01X299952Y587402D01*
Y584098D01*
X299957Y584075D01*
G02X300002Y583700I-1557J-377D01*
G01Y582300D01*
G02X299957Y581925I-1602J2D01*
G01X299952Y581902D01*
Y579598D01*
X299957Y579575D01*
G02X300002Y579200I-1557J-377D01*
G01Y577800D01*
G02X298400Y576198I-1602J0D01*
G01X297000D01*
G02X296000Y576549I1J1602D01*
G02X295000Y576198I-1001J1251D01*
G01X293600D01*
G02X292234Y576965I1J1601D01*
G01X292175Y577060D01*
X291908D01*
X291849Y576969D01*
G02X288391Y576662I-1849J1196D01*
G01X288331Y576726D01*
X287870D01*
X287810Y576643D01*
G02X284350Y580389I-2110J1522D01*
G37*
G36*
G01X221053Y574880D02*
G03X221022Y575507I-263J301D01*
G02X223747Y575640I1278J1793D01*
G03X223778Y575013I263J-301D01*
G02X221053Y574880I-1278J-1793D01*
G37*
G36*
G01X281641Y553333D02*
G03X281658Y553050I150J-133D01*
G02X281758Y552956I-1457J-1651D01*
G03X282042I142J141D01*
G02Y549844I1558J-1556D01*
G03X281758I-142J-141D01*
G02X278553Y552861I-1558J1556D01*
G03X278536Y553144I-150J133D01*
G02X281641Y553333I1458J1650D01*
G37*
G36*
G01X36055Y424560D02*
X35871Y424744D01*
X35784Y424741D01*
G02X37816Y427581I-75J2201D01*
G01X37859Y427440D01*
X38932D01*
G02X40400Y428402I1468J-639D01*
G01X42000D01*
G02X43602Y426800I0J-1602D01*
G01Y425200D01*
G02X43194Y424133I-1602J1D01*
G03Y423867I150J-133D01*
G02X43602Y422800I-1194J-1068D01*
G01Y421200D01*
G02X43601Y421187I-1593J116D01*
G03X43776Y420987I200J-2D01*
G02X41421Y418077I-276J-2185D01*
G01X41406Y418120D01*
X39818Y419707D01*
X39782Y419723D01*
G02X38798Y421200I618J1478D01*
G01Y422800D01*
G02X39206Y423867I1602J-1D01*
G03Y424133I-150J133D01*
G02X38932Y424560I1194J1067D01*
G01X36055D01*
G37*
G36*
G01X19693Y412577D02*
G03X20187Y412225I398J36D01*
G02X18520Y409884I526J-2138D01*
G03X18026Y410236I-398J-36D01*
G02X19693Y412577I-526J2138D01*
G37*
G36*
G01X36671Y375717D02*
G03X36000I-335J-218D01*
G02Y378115I-1847J1199D01*
G03X36671I336J218D01*
G02Y375717I1847J-1199D01*
G37*
G36*
G01X52078Y347987D02*
G03X51938Y348234I-193J54D01*
G02X54643Y349770I583J2123D01*
G03X54783Y349523I193J-54D01*
G02X52078Y347987I-583J-2123D01*
G37*
G36*
G01X54752Y332498D02*
Y331248D01*
X46848D01*
Y338152D01*
X54752D01*
Y336902D01*
X58912D01*
X59657Y336157D01*
G02X59948Y335796I-1559J-1554D01*
G03X60609Y335781I336J218D01*
G02X60551Y333304I1791J-1281D01*
G03X59890Y333319I-336J-218D01*
G02X57471Y332490I-1791J1281D01*
G01X57443Y332498D01*
X54752D01*
G37*
G36*
G01X27799Y251735D02*
G03Y251064I218J-335D01*
G02X25401I-1199J-1847D01*
G03Y251735I-218J335D01*
G02X27799I1199J1847D01*
G37*
G36*
G01X78000Y226878D02*
X73600D01*
G02Y231700I0J2411D01*
G01X78000D01*
G02X80412Y229299I0J-2412D01*
G01Y229200D01*
X80405Y229112D01*
G02X78000Y226878I-2405J178D01*
G37*
G36*
G01X92659Y220772D02*
X88259D01*
G02Y225596I0J2412D01*
G01X92659D01*
G02X95070Y223194I0J-2411D01*
G01Y223095D01*
X95064Y223007D01*
G02X92659Y220772I-2405J176D01*
G37*
G36*
G01X41250Y214716D02*
X38050D01*
G02Y218740I0J2012D01*
G01X41251D01*
G02X43262Y216738I-1J-2012D01*
G01Y216641D01*
X43254Y216554D01*
G02X41250Y214716I-2004J173D01*
G37*
G36*
G01X77400Y214516D02*
X74200D01*
G02Y218540I0J2012D01*
G01X77401D01*
G02X79412Y216538I-1J-2012D01*
G01Y216441D01*
X79404Y216354D01*
G02X77400Y214516I-2004J173D01*
G37*
G36*
G01X56600Y209916D02*
X53399D01*
G02X53400Y213940I1J2012D01*
G01X56600D01*
G02X58612Y211938I0J-2012D01*
G01Y211841D01*
X58604Y211754D01*
G02X56600Y209916I-2004J173D01*
G37*
G36*
G01X92000Y208840D02*
X88799D01*
G02X88800Y212862I1J2011D01*
G01X92000D01*
G02X94012Y210861I0J-2012D01*
G01Y210764D01*
X94004Y210677D01*
G02X92000Y208840I-2004J175D01*
G37*
G36*
G01X101301Y151622D02*
Y151524D01*
X101297Y151430D01*
G02Y151808I-5108J189D01*
G01X101300Y151716D01*
X101301Y151624D01*
Y151622D01*
G37*
G36*
G01X32089D02*
Y151524D01*
X32085Y151430D01*
G02Y151808I-5108J189D01*
G01X32088Y151716D01*
X32089Y151624D01*
Y151622D01*
G37*
G36*
G01X27626Y541281D02*
G02X27166Y539308I1674J-1430D01*
G03X26474Y539469I-388J-98D01*
G02X26934Y541442I-1674J1430D01*
G03X27626Y541281I388J98D01*
G37*
G36*
G01X73231Y186422D02*
G02Y188774I-3616J1176D01*
G03X73991I380J123D01*
G02X81223I3616J-1176D01*
G03X81983I380J123D01*
G02Y186422I3616J-1176D01*
G03X81223I-380J-123D01*
G02X73991I-3616J1176D01*
G03X73231I-380J-123D01*
G37*
G36*
G01X41183D02*
G02Y188774I-3616J1176D01*
G03X41943I380J123D01*
G02X49175I3616J-1176D01*
G03X49935I380J123D01*
G02Y186422I3616J-1176D01*
G03X49175I-380J-123D01*
G02X41943I-3616J1176D01*
G03X41183I-380J-123D01*
G37*
G36*
G01X45219Y176422D02*
G02Y178774I-3616J1176D01*
G03X45979I380J123D01*
G02X53211I3616J-1176D01*
G03X53971I380J123D01*
G02X61203I3616J-1176D01*
G03X61963I380J123D01*
G02X69195I3616J-1176D01*
G03X69955I380J123D01*
G02X77187I3616J-1176D01*
G03X77947I380J123D01*
G02Y176422I3616J-1176D01*
G03X77187I-380J-123D01*
G02X69955I-3616J1176D01*
G03X69195I-380J-123D01*
G02X61963I-3616J1176D01*
G03X61203I-380J-123D01*
G02X53971I-3616J1176D01*
G03X53211I-380J-123D01*
G02X45979I-3616J1176D01*
G03X45219I-380J-123D01*
G37*
G36*
G01X147665Y151970D02*
G02Y155116I-3571J1573D01*
G03X148397I366J161D01*
G02Y151970I3571J-1573D01*
G03X147665I-366J-161D01*
G37*
G36*
G01X466463Y59478D02*
G02X464530Y59847I-1336J-1751D01*
G03X464664Y60549I-109J385D01*
G02X466597Y60180I1336J1751D01*
G03X466463Y59478I109J-385D01*
G37*
G36*
G01X50570Y301016D02*
Y300216D01*
X50577Y299971D01*
Y299171D01*
X49777D01*
Y299971D01*
X49770Y300216D01*
Y301016D01*
X50570D01*
G37*
G36*
G01X56570D02*
Y300216D01*
X56577Y299971D01*
Y299171D01*
X55777D01*
Y299971D01*
X55770Y300216D01*
Y301016D01*
X56570D01*
G37*
G36*
G01X933184Y55919D02*
G03X932559Y55909I-309J-255D01*
G02X927909Y57260I-2059J1591D01*
G03X927376Y57600I-398J-37D01*
G02X929091Y60290I-876J2450D01*
G03X929624Y59950I398J37D01*
G02X932681Y58919I876J-2450D01*
G03X933303Y58858I335J218D01*
G02X936418Y58899I1578J-1536D01*
G03X937061Y59019I279J286D01*
G02X937527Y56527I2003J-915D01*
G03X936884Y56407I-279J-286D01*
G02X933184Y55919I-2003J915D01*
G37*
G36*
G01X628548Y373215D02*
G03X628801Y373088I190J63D01*
G02X627410Y370306I699J-2088D01*
G03X627157Y370433I-190J-63D01*
G02X628548Y373215I-699J2088D01*
G37*
G36*
G01X616505Y347123D02*
G03X616201Y347575I-395J62D01*
G02X618881Y349375I505J2143D01*
G03X619185Y348923I395J-62D01*
G02X616505Y347123I-505J-2143D01*
G37*
G36*
G01X958998Y236974D02*
Y237721D01*
X959688Y238411D01*
X959701Y238469D01*
G02X961435Y236900I1322J-281D01*
G03X961297Y236688I61J-190D01*
G02X961302Y236610I-697J-84D01*
G01Y235810D01*
G02X960600Y235108I-702J0D01*
G01X959600D01*
G02X958898Y235810I0J702D01*
G01Y236610D01*
G02X958976Y236931I702J-1D01*
G01X958998Y236974D01*
G37*
G36*
G01X953502Y235810D02*
G02X952800Y235108I-702J0D01*
G01X951800D01*
G02X951098Y235810I0J702D01*
G01Y236610D01*
G02X951176Y236931I702J-1D01*
G01X951198Y236974D01*
Y237795D01*
X951814Y238411D01*
X951827Y238469D01*
G02X953623Y236922I1322J-281D01*
G03X953495Y236707I70J-187D01*
G02X953502Y236610I-695J-99D01*
G01Y235810D01*
G37*
G36*
G01X934787Y238469D02*
X934800Y238411D01*
X935502Y237709D01*
Y236974D01*
X935524Y236931D01*
G02X935602Y236610I-624J-322D01*
G01Y235810D01*
G02X934900Y235108I-702J0D01*
G01X933900D01*
G02X933198Y235810I0J702D01*
G01Y236610D01*
G02X933203Y236685I701J-9D01*
G03X933063Y236897I-199J21D01*
G02X934787Y238469I402J1291D01*
G37*
G36*
G01X958431Y234386D02*
X958438Y234315D01*
X958902Y233852D01*
Y233191D01*
G02X959102Y232700I-503J-491D01*
G01Y231900D01*
G02X958400Y231198I-702J0D01*
G01X957400D01*
G02X956698Y231900I0J702D01*
G01Y232700D01*
G02X956704Y232787I702J-5D01*
G03X956580Y232997I-198J24D01*
G02X958431Y234386I506J1254D01*
G37*
G36*
G01X950534Y234532D02*
X950547Y234474D01*
X951202Y233819D01*
Y233064D01*
X951224Y233021D01*
G02X951302Y232700I-624J-322D01*
G01Y231900D01*
G02X950600Y231198I-702J0D01*
G01X949600D01*
G02X948898Y231900I0J702D01*
G01Y232700D01*
G02X948902Y232766I701J-9D01*
G03X948768Y232974I-199J19D01*
G02X950534Y234532I444J1277D01*
G37*
G36*
G01X929802Y231900D02*
G02X929100Y231198I-702J0D01*
G01X928100D01*
G02X927398Y231900I0J702D01*
G01Y232700D01*
G02X927476Y233021I702J-1D01*
G01X927498Y233064D01*
Y233779D01*
X928193Y234474D01*
X928206Y234532D01*
G02X929938Y232963I1322J-281D01*
G03X929799Y232756I61J-191D01*
G02X929802Y232700I-698J-65D01*
G01Y231900D01*
G37*
G36*
G01X958998Y229091D02*
Y229847D01*
X959688Y230537D01*
X959701Y230595D01*
G02X961434Y229026I1322J-281D01*
G03X961296Y228811I61J-191D01*
G02X961302Y228727I-695J-92D01*
G01Y227927D01*
G02X960600Y227226I-702J1D01*
G01X959600D01*
G02X958898Y227927I-1J701D01*
G01Y228727D01*
G02X958976Y229048I702J-1D01*
G01X958998Y229091D01*
G37*
G36*
G01X951198D02*
Y229921D01*
X951814Y230537D01*
X951827Y230595D01*
G02X953622Y229047I1322J-281D01*
G03X953494Y228830I70J-187D01*
G02X953502Y228727I-694J-106D01*
G01Y227927D01*
G02X952800Y227226I-702J1D01*
G01X951800D01*
G02X951098Y227927I-1J701D01*
G01Y228727D01*
G02X951176Y229048I702J-1D01*
G01X951198Y229091D01*
G37*
G36*
G01X934787Y230595D02*
X934800Y230537D01*
X935502Y229835D01*
Y229091D01*
X935524Y229048D01*
G02X935602Y228727I-624J-322D01*
G01Y227927D01*
G02X934900Y227226I-702J1D01*
G01X933900D01*
G02X933198Y227927I-1J701D01*
G01Y228727D01*
G02X933203Y228809I702J-2D01*
G03X933064Y229023I-199J23D01*
G02X934787Y230595I401J1291D01*
G37*
G36*
G01X927498Y225164D02*
Y225905D01*
X928193Y226600D01*
X928206Y226658D01*
G02X929936Y225088I1322J-281D01*
G03X929797Y224876I60J-191D01*
G02X929802Y224800I-696J-84D01*
G01Y224000D01*
G02X929100Y223298I-702J0D01*
G01X928100D01*
G02X927398Y224000I0J702D01*
G01Y224800D01*
G02X927476Y225121I702J-1D01*
G01X927498Y225164D01*
G37*
G36*
G01X941061Y231641D02*
X941159Y231654D01*
G02X940602Y229180I180J-1340D01*
G01X940553Y229212D01*
X940374D01*
X938398Y231188D01*
Y231536D01*
X938376Y231579D01*
G02X938298Y231900I624J322D01*
G01Y232700D01*
G02X938311Y232834I697J0D01*
G03X938023Y233050I-196J39D01*
G02X937918Y233001I-624J1200D01*
G03X937796Y232791I76J-185D01*
G02X937802Y232700I-696J-92D01*
G01Y231900D01*
G02X937100Y231198I-702J0D01*
G01X936100D01*
G02X935398Y231900I0J702D01*
G01Y232700D01*
G02X935476Y233021I702J-1D01*
G01X935498Y233064D01*
Y233905D01*
X936067Y234474D01*
X936080Y234532D01*
G02X938621Y233666I1322J-281D01*
G03X938845Y233384I180J-87D01*
G02X939000Y233402I158J-684D01*
G01X940000D01*
G02X940702Y232700I0J-702D01*
G01Y232000D01*
X941061Y231641D01*
G37*
G36*
G01X941039Y223762D02*
X941139Y223777D01*
G02X940602Y221306I200J-1337D01*
G01X940553Y221338D01*
X940348D01*
X938398Y223288D01*
Y223636D01*
X938376Y223679D01*
G02X938298Y224000I624J322D01*
G01Y224800D01*
G02X938316Y224957I702J-1D01*
G03X938029Y225179I-195J45D01*
G02X937915Y225126I-626J1198D01*
G03X937793Y224910I75J-185D01*
G02X937802Y224800I-693J-112D01*
G01Y224000D01*
G02X937100Y223298I-702J0D01*
G01X936100D01*
G02X935398Y224000I0J702D01*
G01Y224800D01*
G02X935476Y225121I702J-1D01*
G01X935498Y225164D01*
Y226031D01*
X936067Y226600D01*
X936080Y226658D01*
G02X938608Y225766I1322J-280D01*
G03X938834Y225482I179J-90D01*
G02X939000Y225502I166J-682D01*
G01X940000D01*
G02X940702Y224800I0J-702D01*
G01Y224100D01*
X941039Y223762D01*
G37*
G36*
G01X683600Y376706D02*
X680099D01*
G02X680100Y380730I1J2012D01*
G01X683600D01*
G02X685612Y378728I0J-2012D01*
G01Y378631D01*
X685604Y378544D01*
G02X683600Y376706I-2004J173D01*
G37*
G36*
G01X823303Y285362D02*
Y285265D01*
X823298Y285172D01*
G02Y285546I-4007J187D01*
G01X823302Y285455D01*
X823303Y285364D01*
Y285362D01*
G37*
G36*
G01Y265362D02*
Y265265D01*
X823298Y265172D01*
G02Y265546I-4007J187D01*
G01X823302Y265455D01*
X823303Y265364D01*
Y265362D01*
G37*
G36*
G01X982502Y215741D02*
Y214802D01*
X982043Y214343D01*
X982030Y214285D01*
G02X980101Y215774I-1322J281D01*
G03X980209Y215987I-89J179D01*
G02X980198Y216105I690J124D01*
G01Y216905D01*
G02X980900Y217606I702J-1D01*
G01X981900D01*
G02X982602Y216905I1J-701D01*
G01Y216105D01*
G02X982524Y215784I-702J1D01*
G01X982502Y215741D01*
G37*
G36*
G01X977243Y215998D02*
G03X977354Y215786I197J-32D01*
G02X975449Y214285I-583J-1220D01*
G01X975436Y214343D01*
X974948Y214831D01*
Y215746D01*
X974926Y215789D01*
G02X974848Y216110I624J322D01*
G01Y216910D01*
G02X975550Y217612I702J0D01*
G01X976550D01*
G02X977252Y216910I0J-702D01*
G01Y216110D01*
G02X977243Y215998I-701J0D01*
G37*
G36*
G01X919402Y215786D02*
Y214693D01*
X919052Y214343D01*
X919039Y214285D01*
G02X917034Y215733I-1322J281D01*
G03X917125Y215959I-102J172D01*
G02X917098Y216150I675J193D01*
G01Y216950D01*
G02X917800Y217652I702J0D01*
G01X918800D01*
G02X919502Y216950I0J-702D01*
G01Y216150D01*
G02X919424Y215829I-702J1D01*
G01X919402Y215786D01*
G37*
G36*
G01X914099Y216045D02*
G03X914232Y215840I200J-16D01*
G02X912458Y214285I-452J-1274D01*
G01X912445Y214343D01*
X911798Y214990D01*
Y215736D01*
X911776Y215779D01*
G02X911698Y216100I624J322D01*
G01Y216900D01*
G02X912400Y217602I702J0D01*
G01X913400D01*
G02X914102Y216900I0J-702D01*
G01Y216100D01*
G02X914099Y216045I-701J11D01*
G37*
G36*
G01X977450Y204450D02*
X976600D01*
X967050Y214000D01*
Y215050D01*
X968100Y216100D01*
X968391D01*
X968392Y216102D01*
X969408D01*
X969409Y216100D01*
X970000D01*
X972498Y213602D01*
X972511Y213592D01*
G02X972668Y213435I-411J-568D01*
G01X972678Y213422D01*
X978600Y207500D01*
Y205600D01*
X977450Y204450D01*
G37*
G36*
G01X965193Y213111D02*
X965203Y213047D01*
X972467Y205783D01*
X972513Y205768D01*
G02X972968Y205313I-213J-668D01*
G01X972983Y205267D01*
X978550Y199700D01*
Y198750D01*
X978302Y198502D01*
Y198492D01*
X977929Y198120D01*
X977917Y198100D01*
G02X977489Y197672I-1146J718D01*
G01X977469Y197660D01*
X977108Y197298D01*
X976292D01*
X976091Y197500D01*
X975500D01*
X958950Y214050D01*
Y214900D01*
X959950Y215900D01*
X960191D01*
X960442Y216152D01*
X961708D01*
X961959Y215900D01*
X962350D01*
X964547Y213703D01*
X964611Y213693D01*
G02X965193Y213111I-111J-693D01*
G37*
G36*
G01X972832Y192287D02*
X972817Y192333D01*
X951500Y213650D01*
Y215000D01*
X952300Y215800D01*
X952591D01*
X952742Y215952D01*
X953958D01*
X954109Y215800D01*
X954400D01*
X956498Y213702D01*
X956600D01*
G02X957302Y213000I0J-702D01*
G01Y212898D01*
X964398Y205802D01*
X964500D01*
G02X965202Y205100I0J-702D01*
G01Y204998D01*
X978050Y192150D01*
Y191859D01*
X978102Y191808D01*
Y191185D01*
X978104Y191168D01*
G02Y190720I-1333J-224D01*
G01X978102Y190703D01*
Y190392D01*
X978050Y190341D01*
Y190100D01*
X977600Y189650D01*
X977359D01*
X977308Y189598D01*
X976895D01*
G02X976647I-124J1346D01*
G01X976092D01*
X976041Y189650D01*
X975450D01*
X974650Y190450D01*
Y190500D01*
X973333Y191817D01*
X973287Y191832D01*
G02X972832Y192287I213J668D01*
G37*
G36*
G01X982452Y184286D02*
Y183257D01*
X982043Y182848D01*
X982030Y182790D01*
G02X980068Y184262I-1322J281D01*
G03X980168Y184485I-94J176D01*
G02X980148Y184650I682J166D01*
G01Y185450D01*
G02X980850Y186152I702J0D01*
G01X981850D01*
G02X982552Y185450I0J-702D01*
G01Y184650D01*
G02X982474Y184329I-702J1D01*
G01X982452Y184286D01*
G37*
G36*
G01X949293Y213111D02*
X949303Y213047D01*
X956546Y205804D01*
X956625Y205801D01*
G02X957301Y205125I-25J-701D01*
G01X957304Y205046D01*
X972050Y190300D01*
Y190250D01*
X975650Y186650D01*
Y186409D01*
X975652Y186408D01*
Y182892D01*
X975650Y182891D01*
Y182800D01*
X974650Y181800D01*
X974559D01*
X974458Y181698D01*
X972292D01*
X972191Y181800D01*
X972050D01*
X971450Y182400D01*
Y183600D01*
X972450Y184600D01*
Y185350D01*
X966002Y191798D01*
X965700D01*
G02X964998Y192500I0J702D01*
G01Y192802D01*
X945800Y212000D01*
Y213050D01*
X946400Y213650D01*
X946891D01*
X947042Y213802D01*
X948258D01*
X948358Y213702D01*
X948600D01*
G02X949293Y213111I0J-702D01*
G37*
G36*
G01X914102Y180700D02*
G02X913400Y179998I-702J0D01*
G01X912400D01*
G02X911698Y180700I0J702D01*
G01Y181500D01*
G02X911776Y181821I702J-1D01*
G01X911798Y181864D01*
Y182647D01*
X912445Y183294D01*
X912458Y183352D01*
G02X914229Y181796I1322J-281D01*
G03X914097Y181583I66J-189D01*
G02X914102Y181500I-697J-84D01*
G01Y180700D01*
G37*
G36*
G01X916532Y181170D02*
X917239D01*
X917940Y180469D01*
X917998Y180456D01*
G02X916427Y178729I-281J-1322D01*
G03X916221Y178869I-191J-60D01*
G02X916168Y178866I-66J698D01*
G01X915368D01*
G02X914666Y179568I0J702D01*
G01Y180568D01*
G02X915368Y181270I702J0D01*
G01X916168D01*
G02X916489Y181192I-1J-702D01*
G01X916532Y181170D01*
G37*
G36*
G01X977302Y176750D02*
G02X976600Y176048I-702J0D01*
G01X975600D01*
G02X974898Y176750I0J702D01*
G01Y177550D01*
G02X974976Y177871I702J-1D01*
G01X974998Y177914D01*
Y178919D01*
X975436Y179357D01*
X975449Y179415D01*
G02X977387Y177931I1322J-281D01*
G03X977284Y177708I92J-178D01*
G02X977302Y177550I-684J-158D01*
G01Y176750D01*
G37*
G36*
G01X982602Y176386D02*
Y175533D01*
X982043Y174974D01*
X982030Y174916D01*
G02X980184Y176443I-1322J281D01*
G03X980305Y176655I-77J185D01*
G02X980298Y176750I695J99D01*
G01Y177550D01*
G02X981000Y178252I702J0D01*
G01X982000D01*
G02X982702Y177550I0J-702D01*
G01Y176750D01*
G02X982624Y176429I-702J1D01*
G01X982602Y176386D01*
G37*
G36*
G01X955798Y194471D02*
X955783Y194517D01*
X952785Y197515D01*
X952739Y197530D01*
G02X951861Y198408I410J1288D01*
G01X951846Y198454D01*
X948848Y201452D01*
X948802Y201467D01*
G02X948003Y202150I410J1288D01*
G01X943750D01*
X942302Y203598D01*
X942200D01*
G02X941498Y204300I0J702D01*
G01Y204402D01*
X934402Y211498D01*
X934300D01*
G02X933598Y212200I0J702D01*
G01Y212302D01*
X931050Y214850D01*
X933250Y217050D01*
X933591D01*
X933692Y217152D01*
X940608D01*
X942032Y215727D01*
X942052Y215715D01*
G02X942100Y213449I-713J-1149D01*
G01Y212300D01*
X947450Y206950D01*
X948050D01*
X968900Y186100D01*
Y183800D01*
X968350Y183250D01*
Y181859D01*
X978102Y172108D01*
Y172048D01*
X978150Y172000D01*
Y171800D01*
X978102Y171752D01*
Y171501D01*
X978104Y171484D01*
G02Y171036I-1333J-224D01*
G01X978102Y171019D01*
Y170792D01*
X977996Y170687D01*
X977981Y170657D01*
G02X976312Y169988I-1210J603D01*
G01X976280Y170000D01*
X975450D01*
X975351Y170098D01*
X975192D01*
X972898Y172392D01*
Y172454D01*
X972876Y172497D01*
G02X972798Y172818I624J322D01*
G01Y173242D01*
X963748Y182292D01*
Y182469D01*
X963730Y182509D01*
G02X964280Y184240I1230J562D01*
G01X964303Y184253D01*
X964700Y184650D01*
Y185850D01*
X960958Y189592D01*
X960887Y189599D01*
G02X959678Y190808I136J1345D01*
G01X959671Y190879D01*
X959400Y191150D01*
X958300D01*
X957633Y191817D01*
X957587Y191832D01*
G02X957132Y192287I213J668D01*
G01X957117Y192333D01*
X957000Y192450D01*
Y193300D01*
X956722Y193578D01*
X956676Y193593D01*
G02X955798Y194471I410J1288D01*
G37*
G36*
G01X1002198Y236964D02*
Y237614D01*
X1002995Y238411D01*
X1003008Y238469D01*
G02X1004650Y236875I1322J-281D01*
G03X1004499Y236662I48J-194D01*
G02X1004502Y236600I-699J-65D01*
G01Y235800D01*
G02X1004501Y235767I-702J5D01*
G03X1004653Y235564I200J-9D01*
G02X1003101Y234815I-323J-1313D01*
G01X1003120Y234855D01*
Y235098D01*
X1002800D01*
G02X1002098Y235800I0J702D01*
G01Y236600D01*
G02X1002176Y236921I702J-1D01*
G01X1002198Y236964D01*
G37*
G36*
G01X998398Y147201D02*
X998835Y147638D01*
X998398Y148075D01*
Y148854D01*
X998376Y148897D01*
G02X998298Y149218I624J322D01*
G01Y150018D01*
G02X998817Y150695I701J0D01*
G03X999096Y151194I-105J386D01*
G02X999197Y152205I1297J381D01*
G01X999220Y152249D01*
Y152498D01*
X999000D01*
G02X998298Y153200I0J702D01*
G01Y154000D01*
G02X998376Y154321I702J-1D01*
G01X998398Y154364D01*
Y155075D01*
X999058Y155735D01*
X999071Y155793D01*
G02X1000835Y154234I1322J-281D01*
G03X1000701Y154035I66J-189D01*
G02X1000702Y154000I-701J-38D01*
G01Y153200D01*
G02X1000691Y153080I-702J4D01*
G03X1000824Y152856I197J-34D01*
G02X1000832Y150296I-431J-1281D01*
G03X1000698Y150087I65J-189D01*
G02X1000702Y150018I-698J-75D01*
G01Y149218D01*
G02X1000696Y149131I-702J5D01*
G03X1000830Y148917I199J-25D01*
G02X1000831Y146359I-437J-1279D01*
G03X1000697Y146147I65J-189D01*
G02X1000702Y146068I-697J-84D01*
G01Y145268D01*
G02X1000697Y145191I-702J7D01*
G03X1000831Y144980I199J-22D01*
G02X1000834Y142423I-438J-1279D01*
G03X1000700Y142219I65J-189D01*
G02X1000702Y142168I-700J-53D01*
G01Y141368D01*
G02X1000694Y141264I-702J2D01*
G03X1000827Y141044I198J-31D01*
G02X1000828Y138484I-434J-1280D01*
G03X1000695Y138267I65J-189D01*
G02X1000702Y138168I-695J-99D01*
G01Y137368D01*
G02X1000699Y137311I-702J8D01*
G03X1000833Y137105I199J-17D01*
G02X999093Y136197I-440J-1278D01*
G03X998814Y136692I-385J109D01*
G02X998298Y137368I185J676D01*
G01Y138168D01*
G02X998376Y138489I702J-1D01*
G01X998398Y138532D01*
Y139327D01*
X998835Y139764D01*
X998398Y140201D01*
Y141004D01*
X998376Y141047D01*
G02X998298Y141368I624J322D01*
G01Y142168D01*
G02X998813Y142844I701J0D01*
G03X999091Y143337I-107J385D01*
G02X999098Y144089I1302J364D01*
G03X998818Y144590I-383J115D01*
G02X998298Y145268I182J678D01*
G01Y146068D01*
G02X998376Y146389I702J-1D01*
G01X998398Y146432D01*
Y147201D01*
G37*
G36*
G01X1001685Y159848D02*
G02X1000029Y160751I-1292J-399D01*
G03X1000173Y160971I-54J192D01*
G02X1000166Y161068I695J99D01*
G01Y161868D01*
G02X1000868Y162570I702J0D01*
G01X1001956D01*
X1002995Y163609D01*
X1003008Y163667D01*
G02X1004611Y162064I1322J-281D01*
G01X1004553Y162051D01*
X1003984Y161483D01*
G03X1004282Y160800I283J-283D01*
G02X1003134Y160079I48J-1351D01*
G01X1003202Y160209D01*
X1002957Y160455D01*
X1002868Y160366D01*
X1002067D01*
G03X1001685Y159848I0J-400D01*
G37*
G36*
G01X1238110Y147952D02*
X1236506D01*
G02X1234906Y149553I1J1601D01*
G01Y151153D01*
G02X1236508Y152754I1602J-1D01*
G01X1238108D01*
G02X1238924Y152530I-1J-1600D01*
G01X1239092D01*
G02X1239907Y152754I817J-1377D01*
G01X1240047D01*
X1240420Y153127D01*
Y153690D01*
G02X1244822I2201J0D01*
G01Y151303D01*
X1243112Y149593D01*
X1243110Y149513D01*
G02X1241509Y147952I-1601J41D01*
G01X1239907D01*
G02X1239291Y148076I2J1601D01*
G01X1238726D01*
G02X1238110Y147952I-618J1477D01*
G37*
G36*
G01X1176777Y140294D02*
X1176939D01*
G02X1177244Y140435I821J-1375D01*
G03X1177405Y141090I-128J379D01*
G02X1178861Y144490I1456J1388D01*
G01X1182061D01*
G02X1184072Y142488I0J-2011D01*
G01Y142391D01*
X1184065Y142304D01*
G02X1182061Y140466I-2004J173D01*
G01X1180997D01*
G03X1180670Y139837I0J-400D01*
G02X1180960Y138918I-1311J-919D01*
G01Y137318D01*
G02X1179358Y135716I-1602J0D01*
G01X1177758D01*
G02X1177138Y135842I3J1602D01*
G01X1176574D01*
G02X1175959Y135718I-618J1477D01*
G01X1174354D01*
G02X1173716Y135851I1J1601D01*
G01X1173678Y135868D01*
X1173219D01*
X1171660Y137426D01*
X1170822D01*
G02X1170182Y137560I1J1602D01*
G01X1170144Y137576D01*
X1169689D01*
X1169651Y137560D01*
G02X1169007Y137424I-646J1466D01*
G01X1167407D01*
G02X1165806Y139026I1J1602D01*
G01Y140626D01*
G02X1166006Y141401I1602J0D01*
G01Y142819D01*
X1168843Y145657D01*
G02X1171982Y142569I1557J-1557D01*
G01X1171925Y142510D01*
Y142230D01*
X1172422D01*
G02X1173592Y141721I-1J-1602D01*
G01X1173595Y141719D01*
X1174793Y140520D01*
X1175959D01*
G02X1176777Y140294I-2J-1601D01*
G37*
G36*
G01X1216996Y142443D02*
Y139423D01*
X1210312Y132738D01*
X1209404D01*
G02X1208545Y132488I-859J1351D01*
G01X1206945D01*
G02X1206129Y132712I1J1601D01*
G01X1205948D01*
G02X1205137Y132490I-813J1379D01*
G01X1203535D01*
G02X1201934Y134091I0J1601D01*
G01Y135691D01*
G02X1203535Y137292I1601J0D01*
G01X1205137D01*
G02X1205748Y137170I-2J-1601D01*
G01X1206334D01*
G02X1206945Y137292I613J-1480D01*
G01X1208545D01*
G02X1208554Y137291I-171J-1583D01*
G01X1208638D01*
X1212594Y141247D01*
Y142443D01*
G02X1216996I2201J0D01*
G37*
G36*
G01X1205135Y139291D02*
Y140091D01*
X1205935D01*
X1206145Y140090D01*
X1206945D01*
Y139290D01*
X1206145D01*
X1205935Y139291D01*
X1205135D01*
G37*
G36*
G01X1169807Y135426D02*
X1170022Y135428D01*
X1170822D01*
Y134628D01*
X1170022D01*
X1169807Y134626D01*
X1169007D01*
Y135426D01*
X1169807D01*
G37*
G36*
G01X1175956Y132919D02*
Y133719D01*
X1176756D01*
X1176958Y133718D01*
X1177758D01*
Y132918D01*
X1176958D01*
X1176756Y132919D01*
X1175956D01*
G37*
G36*
G01X1145307Y240591D02*
G03X1144693I-307J-255D01*
G02Y243409I-1693J1409D01*
G03X1145307I307J255D01*
G02X1148693I1693J-1409D01*
G03X1149307I307J255D01*
G02Y240591I1693J-1409D01*
G03X1148693I-307J-255D01*
G02X1145307I-1693J1409D01*
G37*
G36*
G01X1206991Y154718D02*
X1203791D01*
G02Y158742I0J2012D01*
G01X1206992D01*
G02X1209002Y156740I-1J-2012D01*
G01Y156643D01*
X1208995Y156556D01*
G02X1206991Y154718I-2004J173D01*
G37*
G36*
G01X1199400Y140840D02*
X1196200D01*
G02Y144862I0J2011D01*
G01X1199401D01*
G02X1201412Y142861I0J-2012D01*
G01Y142764D01*
X1201404Y142677D01*
G02X1199400Y140840I-2004J175D01*
G37*
G36*
G01X1234209Y140452D02*
X1231008D01*
G02X1231009Y144474I1J2011D01*
G01X1234209D01*
G02X1236220Y142473I0J-2011D01*
G01Y142376D01*
X1236213Y142289D01*
G02X1234209Y140452I-2004J175D01*
G37*
G36*
G01X1161307Y136494D02*
X1158106D01*
G02X1158107Y140516I1J2011D01*
G01X1161307D01*
G02X1163318Y138515I0J-2011D01*
G01Y138418D01*
X1163311Y138331D01*
G02X1161307Y136494I-2004J175D01*
G37*
G36*
G01X1225348Y135948D02*
X1222148D01*
G02Y139972I0J2012D01*
G01X1225349D01*
G02X1227360Y137970I-1J-2012D01*
G01Y137873D01*
X1227352Y137786D01*
G02X1225348Y135948I-2004J173D01*
G37*
G36*
G01X1190835Y135888D02*
X1187635D01*
G02Y139910I0J2011D01*
G01X1190836D01*
G02X1192846Y137909I-1J-2011D01*
G01Y137812D01*
X1192839Y137725D01*
G02X1190835Y135888I-2004J175D01*
G37*
G36*
G01X1242900Y135840D02*
X1239700D01*
G02Y139862I0J2011D01*
G01X1242901D01*
G02X1244912Y137861I0J-2012D01*
G01Y137764D01*
X1244904Y137677D01*
G02X1242900Y135840I-2004J175D01*
G37*
G36*
G01X1141900D02*
X1138700D01*
G02Y139862I0J2011D01*
G01X1141901D01*
G02X1143912Y137861I0J-2012D01*
G01Y137764D01*
X1143904Y137677D01*
G02X1141900Y135840I-2004J175D01*
G37*
G36*
G01X1277265Y135662D02*
X1274064D01*
G02X1274065Y139684I1J2011D01*
G01X1277265D01*
G02X1279276Y137683I0J-2011D01*
G01Y137586D01*
X1279269Y137499D01*
G02X1277265Y135662I-2004J175D01*
G37*
G36*
G01X1124012Y133334D02*
Y130037D01*
X1124005Y129950D01*
G02X1119990Y130124I-2004J174D01*
G01Y133325D01*
G02X1124012Y133334I2011J-1D01*
G37*
G36*
G01X1079209Y112136D02*
Y112037D01*
X1079204Y111944D01*
G02Y112318I-4007J187D01*
G01X1079208Y112227D01*
X1079209Y112136D01*
G37*
G36*
G01Y92136D02*
Y92037D01*
X1079204Y91944D01*
G02Y92318I-4007J187D01*
G01X1079208Y92227D01*
X1079209Y92136D01*
G37*
G54D105*
X1239008Y145553D03*
G54D100*
X628750Y345100D03*
X637250Y368100D03*
X628750Y351100D03*
X637250D03*
Y362100D03*
G54D97*
X161000Y507250D03*
Y510750D03*
Y514250D03*
G54D88*
X514309Y-315D03*
X557616D03*
X600923D03*
X644230D03*
X687537D03*
X1116671D03*
X1159978D03*
X1203285D03*
X1246592D03*
X1289899D03*
G54D104*
X1268133Y142634D03*
Y156137D03*
Y148634D03*
Y150137D03*
G54D99*
X501742Y215594D03*
X511742D03*
X521742D03*
X531742D03*
G54D85*
X27300Y229000D03*
X24000Y308700D03*
X24639Y321239D03*
X25350Y389000D03*
X21300Y429500D03*
X20713Y418326D03*
X23720Y472640D03*
X25200Y712650D03*
X17500Y706300D03*
X21250Y742650D03*
X38500Y321400D03*
X31700Y314700D03*
X39866Y371366D03*
X39300Y389557D03*
X36750Y462900D03*
X33900Y469300D03*
X35700Y488500D03*
X55950Y564500D03*
Y572500D03*
X62611Y608289D03*
X62400Y624500D03*
X53000Y645000D03*
X63300Y634800D03*
X47300Y704400D03*
X42300Y704900D03*
X62000Y713000D03*
X63300Y697200D03*
X59100Y705600D03*
X42130Y694440D03*
X77527Y255800D03*
X84226Y577924D03*
X92000Y591200D03*
X69500Y586000D03*
X66000Y604800D03*
X88000Y613600D03*
X81000Y589000D03*
X78300Y637750D03*
X74500Y713400D03*
X91450Y707650D03*
X108631Y168836D03*
X111967Y199632D03*
X103100Y211600D03*
X115000Y717600D03*
X227500Y603500D03*
X255738Y574238D03*
X296200Y566900D03*
X291000Y561450D03*
X281800Y638900D03*
X288400Y626100D03*
Y634200D03*
X292500Y630200D03*
X457700Y62300D03*
X483250Y59480D03*
X474400Y62300D03*
X1339471Y139268D03*
X1340130Y145980D03*
X44029Y272572D03*
X44426Y267408D03*
X42900Y284500D03*
X52050Y316100D03*
X512600Y186500D03*
X510462Y261315D03*
X518277Y288680D03*
X532921Y298436D03*
X509143Y284391D03*
X554149Y200229D03*
X748300Y53800D03*
X858800Y52200D03*
X849906Y804531D03*
X621300Y366900D03*
X639500Y342500D03*
Y371000D03*
X907500Y325000D03*
X908700Y347300D03*
X909500Y338000D03*
X1249250Y390250D03*
X1251801Y144871D03*
G54D101*
X941339Y238188D03*
X937402Y242125D03*
X929528D03*
X941339D03*
X933465D03*
X937402Y253936D03*
X929528D03*
X941339Y249999D03*
X933465D03*
X941339Y246062D03*
X937402Y249999D03*
X933465Y246062D03*
X929528Y249999D03*
X937402Y246062D03*
X929528D03*
X941339Y257873D03*
X937402Y261810D03*
X933465Y257873D03*
X929528Y261810D03*
X941339Y253936D03*
X937402Y257873D03*
X933465Y253936D03*
X929528Y257873D03*
X949212Y242125D03*
X964960D03*
X957086D03*
X961023D03*
X953149D03*
X949212Y261810D03*
Y257873D03*
Y253936D03*
X964960D03*
X957086D03*
X953149Y249999D03*
X949212D03*
Y246062D03*
X961023Y249999D03*
X964960D03*
X961023Y246062D03*
X957086Y249999D03*
X953149Y246062D03*
X964960D03*
X957086D03*
X964960Y261810D03*
X961023Y257873D03*
X957086Y261810D03*
X953149Y257873D03*
X964960D03*
X961023Y253936D03*
X957086Y257873D03*
X953149Y253936D03*
X874410Y230314D03*
Y222440D03*
X882284Y242125D03*
X878347Y234251D03*
Y226377D03*
X882284Y234251D03*
X878347Y230314D03*
X882284Y226377D03*
X878347Y222440D03*
X890158Y246062D03*
X886221Y249999D03*
X882284Y246062D03*
X878347Y249999D03*
X886221Y246062D03*
X878347D03*
X890158Y257873D03*
X886221Y261810D03*
X882284Y257873D03*
X878347Y261810D03*
X890158Y253936D03*
X886221Y257873D03*
X882284Y253936D03*
X878347Y257873D03*
X874410Y139764D03*
Y131890D03*
Y155512D03*
Y147638D03*
X894095Y131890D03*
X886221Y139764D03*
X890158Y135827D03*
X886221Y131890D03*
X890158Y139764D03*
X894095Y135827D03*
X890158Y131890D03*
X878347Y135827D03*
Y139764D03*
X882284Y135827D03*
X878347Y131890D03*
X890158Y159449D03*
X886221Y155512D03*
X890158Y151575D03*
X886221Y147638D03*
X890158Y143701D03*
X894095Y159449D03*
X890158Y155512D03*
X894095Y151575D03*
X890158Y147638D03*
X894095Y143701D03*
X878347Y159449D03*
Y151575D03*
Y143701D03*
X882284Y159449D03*
X878347Y155512D03*
X882284Y151575D03*
X878347Y147638D03*
X882284Y143701D03*
X894095Y206692D03*
Y194881D03*
Y210629D03*
Y198818D03*
Y190944D03*
Y222440D03*
Y230314D03*
Y214566D03*
Y234251D03*
Y226377D03*
Y218503D03*
X921654Y167323D03*
X917717Y171260D03*
Y190944D03*
X972834Y242125D03*
Y246062D03*
X1008267Y135827D03*
Y139764D03*
Y131890D03*
X1004330Y135827D03*
Y139764D03*
Y131890D03*
X1008267Y163386D03*
Y171260D03*
Y159449D03*
Y143701D03*
Y151575D03*
X1000393Y167323D03*
Y175197D03*
X1004330Y143701D03*
X1008267Y147638D03*
X1004330Y151575D03*
X1008267Y155512D03*
Y167323D03*
X1004330Y171260D03*
X1008267Y175197D03*
X1004330Y147638D03*
Y155512D03*
Y167323D03*
X1000393Y171260D03*
X1004330Y175197D03*
X1008267Y210629D03*
Y202755D03*
Y198818D03*
Y190944D03*
Y179134D03*
X1000393Y206692D03*
X996456D03*
X1004330Y202755D03*
X1000393Y194881D03*
Y183071D03*
X1004330Y179134D03*
X1008267Y183071D03*
X1004330Y190944D03*
X1008267Y194881D03*
X1004330Y198818D03*
X1008267Y206692D03*
X1004330Y210629D03*
X1000393Y179134D03*
X1004330Y183071D03*
X1000393Y190944D03*
X1004330Y194881D03*
X1000393Y198818D03*
X1004330Y206692D03*
X1000393Y210629D03*
X1008267Y226377D03*
Y242125D03*
Y238188D03*
Y234251D03*
Y218503D03*
X1000393Y222440D03*
Y230314D03*
Y242125D03*
X980708D03*
X984645D03*
X992519D03*
X1000393Y214566D03*
X1008267D03*
X1004330Y218503D03*
X1008267Y222440D03*
X1004330Y226377D03*
X1008267Y230314D03*
X1004330Y214566D03*
X1000393Y218503D03*
X1004330Y222440D03*
X1000393Y226377D03*
X1004330Y230314D03*
X1000393Y234251D03*
X1004330Y242125D03*
X996456D03*
X988582D03*
X976771D03*
X984645Y246062D03*
X1004330D03*
X996456D03*
X988582D03*
X976771D03*
X1008267D03*
X1000393D03*
X992519D03*
X980708D03*
X1012204Y131890D03*
Y139764D03*
Y135827D03*
Y167323D03*
Y163386D03*
Y175197D03*
Y147638D03*
Y155512D03*
Y143701D03*
Y151575D03*
Y159449D03*
Y171260D03*
Y206692D03*
Y202755D03*
Y194881D03*
Y183071D03*
Y179134D03*
Y190944D03*
Y198818D03*
Y210629D03*
Y222440D03*
Y238188D03*
Y230314D03*
Y214566D03*
Y242125D03*
Y218503D03*
Y226377D03*
Y234251D03*
G54D84*
X31977Y126614D03*
Y116614D03*
X91189Y126614D03*
Y116614D03*
Y136614D03*
G54D98*
X526215Y184000D03*
X565585D03*
G54D83*
X107400Y119000D03*
X1383700Y138500D03*
X1374900Y761800D03*
G54D82*
X92990Y252362D03*
G54D87*
X134251Y153543D03*
G54D79*
X16200Y120100D03*
X1384200Y122800D03*
X1373200Y823500D03*
G54D86*
X122165Y142874D03*
G54D80*
X42587Y151614D03*
X80579D03*
G54D96*
X46000Y423200D03*
Y424800D03*
Y427200D03*
X91260Y567810D03*
X93460D03*
X66582Y294007D03*
Y296407D03*
X56170Y303016D03*
X56000Y305900D03*
X60582Y294007D03*
X50000Y305900D03*
X136351Y620936D03*
X138751D03*
X148651Y622936D03*
X151051D03*
X154651D03*
X157051D03*
X159651D03*
X162051D03*
X164651D03*
X167051D03*
X121551Y625436D03*
X125651D03*
X128051D03*
X151716Y502736D03*
X154116D03*
X160400Y502800D03*
X162600D03*
X145760Y502830D03*
X148160D03*
X142017Y502960D03*
X144417D03*
X155662Y503011D03*
X158062D03*
X141772Y504267D03*
X161000Y504300D03*
X141772Y506667D03*
X142000Y509300D03*
Y511700D03*
X143016Y515920D03*
X161000Y517200D03*
X143016Y518320D03*
X147300Y520500D03*
X149700D03*
X161019Y520520D03*
X143500Y520800D03*
X157300Y521500D03*
X159700D03*
X161019Y522920D03*
X953900Y42400D03*
Y45800D03*
X555331Y360080D03*
X557731D03*
X559331D03*
X561731D03*
X611063Y254308D03*
Y251908D03*
X625800Y345100D03*
X631700D03*
X634300D03*
X636700D03*
X621500Y353400D03*
Y355800D03*
X634300Y368100D03*
X631700Y351100D03*
X634300D03*
X627500Y353400D03*
X638500Y354400D03*
X627500Y355800D03*
X638500Y356800D03*
Y358400D03*
Y360800D03*
X634300Y362100D03*
X714587Y203642D03*
Y200242D03*
X937400Y221180D03*
X949300Y221200D03*
X933600Y225100D03*
X942500D03*
X953100D03*
X960900D03*
X965000Y229000D03*
X929400Y229027D03*
X937400D03*
X949300D03*
X957100D03*
X933600Y233000D03*
X942500D03*
X953100D03*
X960900D03*
X965000Y236900D03*
X929400Y236910D03*
X937400D03*
X949300D03*
X957100D03*
X723587Y200242D03*
Y203642D03*
X894500Y129203D03*
Y138500D03*
Y141014D03*
Y146388D03*
Y148900D03*
Y154262D03*
Y156799D03*
X898300Y130603D03*
Y133177D03*
Y134577D03*
Y137100D03*
Y138500D03*
Y141014D03*
Y142414D03*
Y144988D03*
Y146388D03*
Y148900D03*
Y150300D03*
Y152862D03*
Y154262D03*
Y156799D03*
Y158199D03*
Y160736D03*
X899868Y160768D03*
X898300Y162136D03*
X899868Y162168D03*
X904200Y164600D03*
X898200Y168568D03*
Y169968D03*
Y172518D03*
Y173918D03*
Y176468D03*
Y177868D03*
Y180368D03*
Y181768D03*
X903300Y184500D03*
X898200Y188268D03*
Y189668D03*
Y192218D03*
Y193618D03*
Y196118D03*
Y197518D03*
Y200068D03*
Y201468D03*
Y204018D03*
Y209368D03*
Y211868D03*
Y213268D03*
Y215818D03*
Y217218D03*
Y219768D03*
Y221168D03*
Y223668D03*
Y225068D03*
Y227618D03*
Y229018D03*
Y231568D03*
Y232968D03*
Y235500D03*
X893900Y236900D03*
X898200D03*
X907193Y238600D03*
X908593D03*
X911100D03*
X912500D03*
X915030D03*
X916430D03*
X919000D03*
X920400D03*
X922904Y238700D03*
X931800Y211900D03*
X939700Y204000D03*
X955300Y192200D03*
X963200Y185868D03*
X916468Y177068D03*
X923700Y166038D03*
X955300Y164638D03*
X951368Y158168D03*
X941350Y158200D03*
X992500D03*
X988139Y158315D03*
X992600Y160700D03*
X951368Y160768D03*
X947100Y162200D03*
X947300Y164638D03*
X908000Y166000D03*
X943500Y166038D03*
X988600Y166100D03*
X902000Y168568D03*
X992600D03*
X902000Y169968D03*
X992600D03*
X902000Y172518D03*
X992600Y172568D03*
X902000Y173918D03*
X943500D03*
X992600Y173968D03*
X984500Y176450D03*
X902000Y176468D03*
X992600D03*
X915068Y177068D03*
X984500Y177850D03*
X902000Y177868D03*
X992600D03*
X902000Y180368D03*
X992600D03*
X909900Y180400D03*
Y181800D03*
X984350Y184350D03*
Y185750D03*
X923700Y185868D03*
X959100D03*
X907100Y185900D03*
X987600Y186200D03*
X902000Y188268D03*
X992600D03*
X902000Y189668D03*
X992600D03*
Y192168D03*
X902000Y192218D03*
X992600Y193568D03*
X902000Y193618D03*
Y196118D03*
X992600Y196168D03*
X902000Y197518D03*
X992600Y197568D03*
X902000Y200068D03*
X992600D03*
X902000Y201468D03*
X992600D03*
Y203968D03*
X902000Y204018D03*
X992600Y205368D03*
X902000Y205418D03*
Y207968D03*
X992600D03*
X902000Y209368D03*
X992600D03*
X902000Y211868D03*
X992600D03*
X902000Y213268D03*
X992600D03*
X943500Y213300D03*
X974600Y213324D03*
X909900Y215800D03*
X984400Y215805D03*
X973050Y215810D03*
X902000Y215818D03*
X992600D03*
X921300Y215850D03*
X909900Y217200D03*
X984400Y217205D03*
X973050Y217210D03*
X902000Y217218D03*
X992600D03*
X921300Y217250D03*
X902000Y219768D03*
X992600D03*
X925600Y219780D03*
X933600D03*
X953100Y219800D03*
X960800D03*
X968700D03*
X902000Y221168D03*
X992600D03*
X925600Y221180D03*
X933600D03*
X953100Y221200D03*
X960800D03*
X968700D03*
X902000Y223668D03*
X992600D03*
X902000Y225068D03*
X992600D03*
X902000Y227618D03*
X992600Y227668D03*
X968800Y229000D03*
X902000Y229018D03*
X925600Y229027D03*
X992600Y229068D03*
X902000Y231568D03*
X992600D03*
X902000Y232968D03*
X992600D03*
X971545Y234600D03*
X974100D03*
X975500D03*
X978060D03*
X979460D03*
X981997D03*
X983397D03*
X985900D03*
X987300D03*
X907193Y234800D03*
X908593D03*
X911100D03*
X912500D03*
X915030D03*
X916430D03*
X919000D03*
X920400D03*
X922904Y234900D03*
X902000Y235500D03*
X992600D03*
X944900Y42400D03*
Y45800D03*
X927500Y185868D03*
X947300Y193600D03*
X939700Y184468D03*
X998368Y160768D03*
X996500Y142468D03*
Y144968D03*
Y146368D03*
Y148918D03*
Y150318D03*
Y152900D03*
Y154300D03*
X996300Y156800D03*
Y158200D03*
X996400Y160700D03*
Y162100D03*
X998368Y162168D03*
X992400Y164700D03*
X996400Y168568D03*
Y169968D03*
Y172568D03*
Y173968D03*
Y176468D03*
Y177868D03*
Y180368D03*
Y181768D03*
X991400Y184800D03*
X996400Y188268D03*
Y189668D03*
Y192168D03*
Y193568D03*
Y196168D03*
Y197568D03*
Y200068D03*
Y201468D03*
Y203968D03*
Y209368D03*
Y211868D03*
Y213268D03*
Y215818D03*
Y217218D03*
Y219768D03*
Y221168D03*
Y223668D03*
Y225068D03*
Y227668D03*
Y229068D03*
Y231568D03*
Y232968D03*
Y235500D03*
Y236900D03*
X1000300D03*
X971545Y238400D03*
X974100D03*
X975500D03*
X978060D03*
X979460D03*
X981997D03*
X983397D03*
X985900D03*
X987300D03*
X1161107Y821310D03*
X1164507D03*
X1179758Y133318D03*
X1173956Y133319D03*
X1167007Y135026D03*
X1172822Y135028D03*
X1208945Y139690D03*
X1203135Y139691D03*
X1265232Y142634D03*
X1271034D03*
X1236108Y145553D03*
X1241909D03*
X1265232Y156137D03*
X1322200Y815700D03*
Y819100D03*
X1265232Y148634D03*
X1271034D03*
X1265232Y150137D03*
X1271034D03*
X1329000Y248800D03*
Y251200D03*
G54D93*
X293110Y55906D03*
G54D89*
X1360630Y135826D03*
G54D90*
X336417Y21260D03*
G54D81*
X54378Y237402D03*
G54D103*
X789850Y283464D03*
G54D102*
Y236220D03*
G54D92*
X1333661Y55906D03*
G54D95*
X1376968Y90551D03*
G54D91*
Y21260D03*
G54D94*
X336417Y90551D03*
%LPD*%
G75*
G36*
G01X973454Y176046D02*
X977600Y171900D01*
Y171000D01*
X977200Y170600D01*
X975400D01*
X973863Y172137D01*
X973858Y172143D01*
G03X973717Y172284I-1024J-883D01*
G01X973711Y172289D01*
X973400Y172600D01*
Y173350D01*
X972989Y173761D01*
X972974Y173811D01*
G03X972493Y174292I-674J-193D01*
G01X972443Y174307D01*
X964250Y182500D01*
Y183150D01*
X965500Y184400D01*
Y185850D01*
X959250Y192100D01*
X958300D01*
X957750Y192650D01*
Y193600D01*
X948375Y202975D01*
X943825D01*
X941705Y205095D01*
X941698Y205166D01*
G03X941066Y205798I-698J-66D01*
G01X940995Y205805D01*
X933805Y212995D01*
X933798Y213066D01*
G03X933166Y213698I-698J-66D01*
G01X933095Y213705D01*
X932650Y214150D01*
Y215400D01*
X933900Y216650D01*
X940400D01*
X941925Y215125D01*
Y214000D01*
X941250Y213325D01*
Y212050D01*
X948075Y205225D01*
X948925D01*
X949098Y205051D01*
Y204300D01*
G03X949800Y203598I702J0D01*
G01X950552D01*
X951890Y202260D01*
X951906Y202224D01*
G03X952618Y201512I1243J531D01*
G01X952654Y201496D01*
X955827Y198323D01*
X955843Y198287D01*
G03X956555Y197575I1243J531D01*
G01X956591Y197559D01*
X959764Y194386D01*
X959780Y194350D01*
G03X960492Y193638I1243J531D01*
G01X960528Y193622D01*
X963701Y190449D01*
X963717Y190413D01*
G03X964429Y189701I1243J531D01*
G01X964465Y189685D01*
X964600Y189550D01*
Y189500D01*
X967750Y186350D01*
Y183787D01*
G03Y182355I1147J-716D01*
G01Y181750D01*
X972696Y176804D01*
X972699Y176725D01*
G03X973375Y176049I701J25D01*
G01X973454Y176046D01*
G37*
G36*
G01X969200Y215600D02*
X972595Y212205D01*
X972604Y212137D01*
G03X973213Y211528I696J87D01*
G01X973281Y211519D01*
X977800Y207000D01*
Y206400D01*
X977200Y205800D01*
X976400D01*
X967800Y214400D01*
Y214800D01*
X968600Y215600D01*
X969200D01*
G37*
G36*
G01X961500Y215650D02*
X964997Y212153D01*
X965007Y212089D01*
G03X965589Y211507I693J111D01*
G01X965653Y211497D01*
X972796Y204354D01*
X972799Y204275D01*
G03X973475Y203599I701J25D01*
G01X973554Y203596D01*
X977800Y199350D01*
Y198700D01*
X976900Y197800D01*
X976500D01*
X959900Y214400D01*
Y214900D01*
X960650Y215650D01*
X961500D01*
G37*
G36*
G01X965596Y203604D02*
X977600Y191600D01*
Y190600D01*
X977100Y190100D01*
X976300D01*
X972996Y193404D01*
X972983Y193459D01*
G03X972459Y193983I-683J-159D01*
G01X972404Y193996D01*
X952200Y214200D01*
Y214700D01*
X952950Y215450D01*
X953750D01*
X957104Y212096D01*
X957117Y212041D01*
G03X957641Y211517I683J159D01*
G01X957696Y211504D01*
X965004Y204196D01*
X965017Y204141D01*
G03X965541Y203617I683J159D01*
G01X965596Y203604D01*
G37*
G36*
G01X957753Y203597D02*
X975150Y186200D01*
Y183100D01*
X974250Y182200D01*
X972500D01*
X972000Y182700D01*
Y183200D01*
X973200Y184400D01*
Y185350D01*
X973005Y185545D01*
X973000Y185619D01*
G03X972351Y186268I-700J-51D01*
G01X972277Y186273D01*
X965203Y193347D01*
X965193Y193411D01*
G03X964611Y193993I-693J-111D01*
G01X964547Y194003D01*
X946500Y212050D01*
Y212550D01*
X947250Y213300D01*
X948050D01*
X949096Y212254D01*
X949099Y212175D01*
G03X949775Y211499I701J25D01*
G01X949854Y211496D01*
X957097Y204253D01*
X957107Y204189D01*
G03X957689Y203607I693J111D01*
G01X957753Y203597D01*
G37*
%LPC*%
G75*
G54D101*
X937402Y214566D03*
G54D96*
X959100Y193600D03*
X947300Y204000D03*
X943500Y205400D03*
X939700Y211900D03*
Y213300D03*
%LPD*%
G75*
G54D10*
G01X41250Y422000D02*
Y420682D01*
X43130Y418802D01*
X43500D01*
G01X103200Y825400D02*
X91800D01*
X85500Y819100D01*
Y807700D01*
G01X124822Y545216D02*
Y546078D01*
X123100Y547800D01*
G01X124822Y538917D02*
X122048Y541691D01*
Y541693D01*
G01X181514Y520020D02*
X184057Y522563D01*
X187028D01*
X188978Y524513D01*
G01X216873Y516458D02*
X217042D01*
X217714Y515786D01*
X221214D01*
X222500Y514500D01*
G01X225000Y538250D02*
Y541300D01*
G01X236807Y140322D02*
Y136443D01*
X237500Y135750D01*
G01X243618Y143381D02*
X240737Y140500D01*
X236985D01*
X236807Y140322D01*
G01X245500Y135750D02*
Y138000D01*
X246500Y139000D01*
G01X241500Y135750D02*
Y137500D01*
X243000Y139000D01*
G01X292000Y130000D02*
X323000D01*
X334755Y141755D01*
G01X294500Y145750D02*
X295250Y145000D01*
Y139750D01*
X285500Y130000D01*
G01X294500Y149250D02*
Y152500D01*
G01X286100Y148900D02*
Y153900D01*
G01X276200D02*
X280000D01*
G01X290500Y149250D02*
Y152500D01*
G01X294500Y145750D02*
X290500D01*
G01X275300Y166000D02*
Y161913D01*
X276200Y161013D01*
Y159900D01*
G01X276500Y143300D02*
Y146000D01*
X275000Y147500D01*
G01X282500Y143300D02*
X282300Y143500D01*
Y146700D01*
X280100Y148900D01*
G01X334755Y141755D02*
X337000Y144000D01*
Y162000D01*
G01X554300Y368300D02*
X556531Y366069D01*
Y364830D01*
G01X552720Y364180D02*
Y366720D01*
X554300Y368300D01*
G01X580200Y224000D02*
X581355D01*
X581713Y224358D01*
X584363D01*
G01D02*
Y225393D01*
X586113Y227143D01*
Y229525D01*
X587438Y230850D01*
G01X596500Y226100D02*
X594758Y224358D01*
X592363D01*
G01X592563Y228308D02*
X595692D01*
X596500Y227500D01*
Y226100D01*
G01X588963Y227408D02*
X589500Y227945D01*
Y230035D01*
X591861Y232396D01*
G01X588363Y224358D02*
Y226808D01*
X588963Y227408D01*
G01X582363Y237408D02*
X577192D01*
X576200Y238400D01*
G01X579434Y243270D02*
X585601D01*
X586935Y241936D01*
Y238665D01*
X587400Y238200D01*
G01X576200Y238400D02*
X576127Y238473D01*
Y240254D01*
X579143Y243270D01*
X579434D01*
G01X579900Y427400D02*
X592500Y440000D01*
X1315500D01*
X1344000Y411500D01*
Y326660D01*
X1319166Y301826D01*
X1304986D01*
X1275500Y272340D01*
Y264500D01*
G01X632563Y238108D02*
Y240608D01*
X631063Y242108D01*
G01X645663Y234758D02*
Y231965D01*
X639249Y225551D01*
X633506D01*
X629663Y221708D01*
G01X616718Y238408D02*
X619418D01*
X621263Y236563D01*
Y233308D01*
X621063Y233108D01*
G01X626563Y238108D02*
X627063Y237608D01*
Y233108D01*
G01X628863Y254608D02*
Y249408D01*
X628563Y249108D01*
G01X615813Y253108D02*
X617313Y254608D01*
X621263D01*
G01X892356Y187500D02*
X829500D01*
X808300Y208700D01*
X771100D01*
X763400Y216400D01*
X716734D01*
X716442Y216692D01*
X657445D01*
X655937Y218200D01*
X640400D01*
G01X645663Y238258D02*
Y238923D01*
X642978Y241608D01*
X642463D01*
G01X641963Y238358D02*
Y238608D01*
X638963Y241608D01*
G01X645663Y234758D02*
X645563Y234858D01*
X641963D01*
G01X646600Y363400D02*
X648792Y361208D01*
Y358431D01*
G01X643250Y355600D02*
Y359600D01*
G01D02*
Y360050D01*
X646600Y363400D01*
G01X928000Y289000D02*
X907000Y310000D01*
X713000D01*
G01X957900Y232300D02*
Y233437D01*
X957086Y234251D01*
G01X1317026Y304858D02*
X1313069Y308815D01*
X1293175D01*
X1288490Y313500D01*
X1084500D01*
X1028500Y257500D01*
G01X1289500Y274250D02*
Y271500D01*
X1290000Y271000D01*
G01X1308500Y262500D02*
X1306718Y264282D01*
Y271182D01*
X1306500Y271400D01*
G01X1311200Y250500D02*
Y256500D01*
G01X1293500Y274250D02*
Y271000D01*
G01X1312500Y271400D02*
Y266900D01*
X1312900Y266500D01*
G01X1314000Y286500D02*
Y286030D01*
X1310388Y282418D01*
X1293668D01*
X1289500Y278250D01*
Y277750D01*
G01D02*
X1293500D01*
G01X1324250Y250000D02*
X1319300D01*
X1318800Y250500D01*
G01X1318900Y266500D02*
X1322200D01*
X1322500Y266800D01*
G01X1359000Y279750D02*
Y279162D01*
X1355066Y275228D01*
G01X1361500Y273500D02*
X1359000Y271000D01*
X1354500D01*
G01X1348500Y276500D02*
Y274500D01*
X1352000Y271000D01*
X1354500D01*
G01X1351000Y279750D02*
Y279000D01*
X1348500Y276500D01*
G01X1355000Y279750D02*
X1354750D01*
X1352000Y277000D01*
Y276700D01*
G01X1352500Y267000D02*
Y266500D01*
X1355209Y263791D01*
G01D02*
X1358800Y260200D01*
X1363500D01*
G01X1363300Y254500D02*
X1363500Y254700D01*
Y260200D01*
X700Y19100D03*
X16200Y120100D03*
X27200Y821800D03*
X33800Y872600D03*
X42587Y151614D03*
X80579D03*
X92990Y252362D03*
X116790D03*
X526215Y184000D03*
X565585D03*
X1027722Y-9125D03*
X1054494D03*
X1301120Y173278D03*
Y183908D03*
X1384200Y122800D03*
X1373200Y823500D03*
X1415100Y-36700D03*
X1389800Y879000D03*
G54D20*
X54970Y301816D03*
X54977Y298371D03*
X54800Y307100D03*
X54978Y294934D03*
X44800Y422000D03*
Y426000D03*
X65382Y295207D03*
X140800Y510500D03*
X140572Y505467D03*
X141816Y517120D03*
X142300Y522000D03*
X272800Y759000D03*
X555280Y137538D03*
X555300Y134094D03*
X626300Y354600D03*
X833600Y176200D03*
Y179700D03*
X875100Y52700D03*
X1039817Y14710D03*
X1327800Y250000D03*
G54D11*
G01X47912Y294940D02*
X48622D01*
X48628Y294934D01*
X51428D01*
G01X47355Y303376D02*
X51079Y307100D01*
X51250D01*
G01X47991Y299958D02*
X49849Y301816D01*
X51420D01*
G01X47991Y299958D02*
X49578Y298371D01*
X51427D01*
G01X50800Y334700D02*
X58000D01*
X58100Y334600D01*
G01X57700Y499250D02*
Y499501D01*
X63519Y505320D01*
G01X53600Y499250D02*
X57700D01*
G01X67250Y535000D02*
X64700D01*
X64200Y534500D01*
G01X127746Y-260199D02*
X95746D01*
G01X94600Y277100D02*
X96240Y275460D01*
X98450D01*
G01X85400Y268400D02*
X72800D01*
X72100Y269100D01*
G01X89400Y279300D02*
Y279285D01*
X89250Y279135D01*
Y276649D01*
X89400Y276499D01*
Y274590D01*
X88750Y273940D01*
G01D02*
X85400Y270590D01*
Y268400D01*
G01X68100Y264700D02*
Y268400D01*
X67400Y269100D01*
G01X68100Y255000D02*
Y264700D01*
G01X98020Y307120D02*
Y308626D01*
X101630Y312236D01*
G01X89400Y470400D02*
X91335D01*
X93250Y472315D01*
Y472400D01*
G01X77450Y478600D02*
Y482050D01*
X76100Y483400D01*
G01X93250Y480400D02*
X91197Y478500D01*
X88510Y475813D01*
X85748D01*
G01X74250Y498500D02*
X77148D01*
X77681Y499033D01*
G01X80750Y502500D02*
X77700D01*
G01X80750D02*
Y506500D01*
G01D02*
Y510500D01*
G01Y514500D02*
Y510500D01*
G01X88573Y503935D02*
X88722Y504084D01*
X91937D01*
G01Y500084D02*
Y496084D01*
G01Y504084D02*
Y500084D01*
G01X92370Y549681D02*
Y545681D01*
G01Y541681D02*
Y545681D01*
G01D02*
X90602D01*
X88204Y543283D01*
G01X93286Y530266D02*
X92024D01*
X90258Y528500D01*
X89200D01*
G01X93286Y526266D02*
Y530266D01*
G01X92509Y517567D02*
X90333D01*
X89200Y518700D01*
G01X92509Y517567D02*
Y513567D01*
G01X65600Y543200D02*
X66549Y544149D01*
X67049D01*
X68600Y545700D01*
X70550D01*
G01X80750Y518500D02*
X75700D01*
X75600Y518600D01*
G01X80750Y518500D02*
Y514500D01*
G01X75600Y518600D02*
X73400D01*
X70750Y521250D01*
Y522500D01*
G01X70350Y526900D02*
Y522900D01*
X70750Y522500D01*
G01X127746Y-276199D02*
Y-356199D01*
G01D02*
X1310146D01*
G01X127746Y-311699D02*
X1310146D01*
G01X123746Y-260199D02*
G02I-12000J0D01*
G01X118596D02*
G02I-6850J0D01*
G01X111746Y-276199D02*
Y-244199D01*
G01X127746Y-276199D02*
X1310146D01*
G01X112217Y296435D02*
X111487D01*
X110000Y294948D01*
Y291250D01*
G01X117850Y288100D02*
X120800D01*
X125100Y283800D01*
Y282500D01*
G01X127925Y428093D02*
X130197Y430365D01*
X131658D01*
G01X131659Y426337D02*
X129681D01*
X127925Y428093D01*
G01X103500Y457750D02*
Y454700D01*
G01X120351Y630186D02*
Y633500D01*
G01X126851Y630186D02*
Y633449D01*
G01X124803Y889470D02*
Y880697D01*
G01X130500Y881000D02*
X131103Y881603D01*
G01X128000Y881000D02*
X127953Y881047D01*
G01X117500Y878200D02*
X115921Y879780D01*
G01X117500Y878200D02*
X118504Y879204D01*
G01X121654Y889470D02*
Y879035D01*
G01X115921Y879780D02*
G02X115355Y881145I1365J1366D01*
G01Y889470D01*
G01X118504Y879204D02*
Y889470D01*
G01X121654Y879035D02*
G03X122000Y878200I1181J0D01*
G01X127953Y881047D02*
Y889470D01*
G01X131103Y881603D02*
Y889470D01*
G01X161811Y149441D02*
Y153543D01*
G01D02*
Y157645D01*
G01X157709Y153543D02*
X161811D01*
G01X155026Y212580D02*
X144595Y223011D01*
Y312861D01*
G01X146165Y444876D02*
Y446595D01*
X146150Y446610D01*
Y449240D01*
G01X150150D02*
Y446582D01*
X149838Y446270D01*
Y446190D01*
G01X139019Y443177D02*
X139944Y444102D01*
Y448684D01*
X140500Y449240D01*
G01X155680Y449180D02*
Y447450D01*
X157438Y445692D01*
X159540D01*
G01X165750Y512500D02*
X166400D01*
X167200Y511700D01*
X167498D01*
X168627Y510571D01*
X168916D01*
G01X143217Y498210D02*
Y497471D01*
X140569Y494823D01*
G01X137250Y510500D02*
X134341D01*
X134270Y510571D01*
G01X168916Y504272D02*
X167688Y505500D01*
X165750D01*
G01D02*
Y509000D01*
G01X137022Y505467D02*
X135465D01*
X134270Y504272D01*
G01X146960Y498080D02*
Y494914D01*
X146869Y494823D01*
G01X152916Y497986D02*
X153168Y497734D01*
Y494823D01*
G01X156862Y498261D02*
X159467Y495656D01*
Y494823D01*
G01X165769Y521720D02*
X167466D01*
X168916Y523170D01*
G01X148500Y525250D02*
Y527838D01*
X146869Y529469D01*
G01X138750Y522000D02*
X135440D01*
X134270Y523170D01*
G01X181000Y595200D02*
X177871Y592071D01*
Y563337D01*
X159134Y544600D01*
X158748D01*
X156500Y542352D01*
Y532696D01*
X153273Y529469D01*
X153168D01*
G01X165750Y516000D02*
X166400D01*
X167270Y516870D01*
X168916D01*
G01X138266Y517120D02*
X134521D01*
X134270Y516869D01*
G01X158500Y526250D02*
Y528502D01*
X159467Y529469D01*
G01X137551Y625686D02*
Y629849D01*
G01X149851Y627686D02*
Y631251D01*
G01X155851Y627686D02*
Y631051D01*
G01X160851Y627686D02*
Y630651D01*
G01X146851Y880851D02*
Y889470D01*
G01X143701Y880644D02*
Y889470D01*
G01X137500Y881000D02*
X137402Y881098D01*
G01X134500Y881000D02*
X134252Y881248D01*
G01X140551Y889470D02*
Y878149D01*
G01X150000Y889470D02*
Y878000D01*
G01X134252Y881248D02*
Y889470D01*
G01X137402Y881098D02*
Y889470D01*
G01X140551Y878149D02*
X141000Y877700D01*
G01X150000Y878000D02*
X149700Y877700D01*
G01X182300Y407850D02*
X177550D01*
G01X181750Y443300D02*
X177153D01*
X176098Y444355D01*
G01X185250Y443300D02*
Y452080D01*
X186675Y453505D01*
G01X193600Y443650D02*
X189600D01*
G01X197800Y443750D02*
X193700D01*
X193600Y443650D01*
G01X201800Y443750D02*
X197800D01*
G01X185250Y443300D02*
X189250D01*
X189600Y443650D01*
G01X197850Y437450D02*
X197995Y437595D01*
X202638D01*
G01X185500Y457750D02*
X185501Y457749D01*
Y454679D01*
X186675Y453505D01*
G01X181750Y517500D02*
Y519784D01*
X181514Y520020D01*
G01X197500Y574250D02*
X201500D01*
G01X197500Y577300D02*
Y574250D01*
G01X191500Y584750D02*
X190250D01*
X185500Y580000D01*
Y577300D01*
G01X165851Y627686D02*
Y630651D01*
G01X194095Y889470D02*
Y879850D01*
X195669Y878276D01*
G01X184646Y889470D02*
Y879054D01*
X185500Y878200D01*
G01X175197Y889470D02*
Y879850D01*
X176771Y878276D01*
G01X228007Y123787D02*
X228973D01*
X232600Y120159D01*
Y102050D01*
G01X236800Y101950D02*
X232700D01*
X232600Y102050D01*
G01X228500Y142700D02*
Y138100D01*
G01X220384Y178059D02*
Y166066D01*
X224450Y162000D01*
X228500D01*
G01Y150300D02*
Y156000D01*
G01Y150300D02*
X231300Y147500D01*
X236500D01*
G01X220384Y178059D02*
Y181384D01*
X223000Y184000D01*
G01X200500Y408250D02*
X205750D01*
G01X201800Y443750D02*
X204350D01*
X205200Y442900D01*
G01D02*
X206776Y444476D01*
Y448165D01*
G01X220800Y446000D02*
Y441897D01*
X220864Y441833D01*
X220897D01*
G01X220800Y446000D02*
X219824Y446976D01*
X219074D01*
X217850Y448200D01*
G01X220897Y441833D02*
X220800Y441736D01*
Y435433D01*
X220838Y435395D01*
G01X230571Y469767D02*
X236317D01*
X240150Y473600D01*
G01X230572Y458863D02*
Y455128D01*
G01X213500Y495744D02*
X215744D01*
X216550Y496550D01*
X216600D01*
G01X219800Y493700D02*
X219690Y493810D01*
X219000D01*
X216934Y491744D01*
X213500D01*
G01X218906Y483186D02*
X220892Y481200D01*
X232278D01*
X234893Y483815D01*
Y485929D01*
G01X221000Y538250D02*
X217000D01*
G01X221000Y541300D02*
Y538250D01*
G01Y518250D02*
X225000D01*
G01X217500Y519800D02*
X217800D01*
X219350Y518250D01*
X221000D01*
G01X225000Y529250D02*
X221000D01*
G01D02*
X217500D01*
G01X216300Y546350D02*
X216150Y546500D01*
X213250D01*
G01D02*
Y542500D01*
G01D02*
Y538500D01*
G01X229000Y518250D02*
X229550Y517700D01*
X235500D01*
X236100Y517100D01*
G01X229000Y529250D02*
X230750D01*
X231276Y529776D01*
X251224D01*
X254700Y526300D01*
X263300D01*
G01X213250Y550500D02*
X216300D01*
G01X216563Y555908D02*
Y555576D01*
X217639Y554500D01*
X222750D01*
G01X231890Y889470D02*
Y879850D01*
X233464Y878276D01*
G01X228740Y889470D02*
Y879850D01*
X227166Y878276D01*
G01X219292Y889470D02*
Y879850D01*
X220866Y878276D01*
G01X216142Y889470D02*
Y879851D01*
X214567Y878276D01*
G01X206693Y889470D02*
Y879850D01*
X208267Y878276D01*
G01X203544Y889470D02*
Y879851D01*
X201969Y878276D01*
G01X249995Y102208D02*
X237058D01*
X236800Y101950D01*
G01X245500Y132250D02*
X249530D01*
G01X241500D02*
X245500D01*
G01X237500D02*
X241500D01*
G01X249530D02*
X253250D01*
X254000Y131500D01*
G01X236500Y147500D02*
X243500D01*
G01X239750Y482000D02*
Y478000D01*
G01D02*
Y474000D01*
X240150Y473600D01*
G01X234893Y477829D02*
X239579D01*
X239750Y478000D01*
G01X234893Y477829D02*
Y473829D01*
G01X240150Y455600D02*
X236400D01*
X235850Y455050D01*
G01X243200Y508000D02*
X243048D01*
X241048Y506000D01*
X234850D01*
G01D02*
Y502000D01*
G01X250200Y506600D02*
Y502450D01*
X251000Y501650D01*
G01X239750Y486000D02*
Y482000D01*
G01X234893Y489929D02*
X234964Y490000D01*
X239750D01*
G01X234893Y489929D02*
Y485929D01*
G01X239750Y486000D02*
Y490000D01*
G01X263181Y772181D02*
X282378D01*
G01X266536Y889470D02*
Y879850D01*
X268110Y878276D01*
G01X263386Y889470D02*
Y879851D01*
X261811Y878276D01*
G01X253937Y889470D02*
Y879850D01*
X255511Y878276D01*
G01X241339Y889470D02*
Y880166D01*
X240961Y879788D01*
Y879473D01*
X239764Y878276D01*
G01X287800Y311600D02*
X293900Y305500D01*
X299800D01*
G01D02*
X315500D01*
X326041Y316041D01*
Y325000D01*
G01X297750Y578500D02*
Y583000D01*
G01Y592750D02*
Y588500D01*
G01D02*
Y583000D01*
G01X290500Y719750D02*
Y719500D01*
X294000Y716000D01*
G01X273500Y732650D02*
X270000D01*
G01X290178Y732681D02*
X285750D01*
X283161Y730092D01*
G01X273500Y736150D02*
X269500D01*
G01X289819Y736181D02*
X290178D01*
G01X300500Y715613D02*
X302406Y717519D01*
Y719515D01*
X302554Y719663D01*
G01X286500Y740500D02*
Y739500D01*
X289819Y736181D01*
G01X285000Y748750D02*
X286500Y747250D01*
Y740500D01*
G01X301000Y744250D02*
Y741800D01*
X302000Y740800D01*
G01X267500Y748750D02*
Y738150D01*
X269500Y736150D01*
G01X270556Y716702D02*
X273502Y719648D01*
X274406D01*
G01X302554Y719663D02*
X298554D01*
G01X278406Y719648D02*
X282406D01*
G01X278406D02*
X274406D01*
G01X282406D02*
X286406D01*
G01X294506D02*
X294521Y719663D01*
X298554D01*
G01X301500Y780100D02*
Y778800D01*
X298400Y775700D01*
G01X272750Y759000D02*
X272500Y758750D01*
Y755976D01*
X272116Y755592D01*
G01X269250Y759000D02*
X268900Y758650D01*
Y756340D01*
X268193Y755633D01*
G01X295079Y772100D02*
X295320Y772341D01*
X299164D01*
G01X282378Y772181D02*
X282411Y772148D01*
X286906D01*
G01X295079Y772100D02*
X286954D01*
X286906Y772148D01*
G01X299164Y772341D02*
X303213D01*
X303406Y772148D01*
G01X288583Y889470D02*
Y879851D01*
X287008Y878276D01*
G01X279134Y889470D02*
Y879850D01*
X280708Y878276D01*
G01X275985Y889470D02*
Y879851D01*
X274410Y878276D01*
G01X334200Y299600D02*
X330400Y303400D01*
X323200D01*
X321300Y301500D01*
G01D02*
Y298850D01*
X312900Y290450D01*
G01X351515Y327915D02*
X338505D01*
X321920Y344500D01*
X315300D01*
G01X322178Y732681D02*
Y729178D01*
G01X306178Y732681D02*
X306319D01*
X309207Y729793D01*
X310016D01*
G01X317000Y744750D02*
Y739600D01*
X317300Y739300D01*
G01X302554Y719663D02*
X302948Y719269D01*
X310027D01*
X310406Y719648D01*
G01X322178Y736181D02*
X320419D01*
X317300Y739300D01*
G01X306178Y736181D02*
X305819D01*
X302000Y740000D01*
Y740800D01*
G01X329528Y889470D02*
Y879850D01*
X331102Y878276D01*
G01X326378Y889470D02*
Y879851D01*
X324803Y878276D01*
G01X316929Y889470D02*
Y879850D01*
X318503Y878276D01*
G01X313780Y889470D02*
Y879480D01*
X312500Y878200D01*
G01X304331Y889470D02*
Y870869D01*
X306500Y868700D01*
G01X364174Y889470D02*
Y879851D01*
X362599Y878276D01*
G01X354725Y889470D02*
Y879850D01*
X356299Y878276D01*
G01X351575Y889470D02*
Y879851D01*
X350000Y878276D01*
G01X342126Y889470D02*
Y879850D01*
X343700Y878276D01*
G01X338977Y889470D02*
Y879851D01*
X337402Y878276D01*
G01X401969Y889470D02*
Y879850D01*
X403543Y878276D01*
G01X398819Y889470D02*
Y879851D01*
X397244Y878276D01*
G01X389370Y889470D02*
Y879850D01*
X390944Y878276D01*
G01X386221Y889470D02*
Y879851D01*
X384646Y878276D01*
G01X376772Y889470D02*
Y879850D01*
X378346Y878276D01*
G01X430315Y889470D02*
Y879850D01*
X431889Y878276D01*
G01X424016Y889470D02*
Y879851D01*
X422441Y878276D01*
G01X414567Y889470D02*
Y879850D01*
X416141Y878276D01*
G01X411418Y889470D02*
Y879851D01*
X409843Y878276D01*
G01X464086Y340500D02*
Y287614D01*
G01X439764Y889470D02*
Y879851D01*
X438189Y878276D01*
G01X489680Y130055D02*
Y128469D01*
X491466Y126683D01*
G01D02*
X493245Y128462D01*
Y130075D01*
G01X506006Y126183D02*
X502322D01*
X500332Y128173D01*
Y130214D01*
G01Y133714D02*
X503767D01*
X503827Y133654D01*
G01X493245Y133575D02*
X496042D01*
X496782Y134315D01*
G01X493245Y133575D02*
X489700D01*
X489680Y133555D01*
G01X503178Y784681D02*
X500089D01*
X497086Y781678D01*
X496061D01*
G01X487906Y771648D02*
X486002D01*
X483850Y773800D01*
G01X499906Y771648D02*
X495906D01*
G01X487906D02*
X491906D01*
G01X495906D02*
X491906D01*
G01X487000Y784650D02*
X483500D01*
G01X488500Y808250D02*
X485300D01*
G01X488500Y811750D02*
X485300D01*
G01X487000Y788150D02*
X483000D01*
G01X498000Y800750D02*
Y794000D01*
X499000Y793000D01*
G01X480800Y800750D02*
X477200Y797150D01*
Y791900D01*
X480950Y788150D01*
X483000D01*
G01X503178Y788181D02*
X501319D01*
X499000Y790500D01*
Y793000D01*
G01X477206Y820648D02*
X480739Y824181D01*
X495878D01*
G01D02*
X495911Y824148D01*
X500406D01*
G01X508579Y824100D02*
X500454D01*
X500406Y824148D01*
G01X522646Y-276199D02*
Y-356199D01*
G01X514309Y-3517D02*
Y-315D01*
G01D02*
Y2887D01*
G01X511107Y-315D02*
X514309D01*
G01D02*
X517511D01*
G01X503827Y130154D02*
X506006Y127975D01*
Y126183D01*
G01X507861Y134154D02*
X507361Y133654D01*
X503827D01*
G01X535178Y784681D02*
Y781000D01*
G01X509600Y771450D02*
Y770515D01*
X510506Y769609D01*
Y769594D01*
X511800Y768300D01*
G01X519069Y785217D02*
X520491D01*
X522078Y783630D01*
Y783009D01*
X522500Y782587D01*
Y782031D01*
G01X515900Y768300D02*
Y768600D01*
X517800Y770500D01*
Y771450D01*
G01X513700D02*
X517800D01*
G01D02*
X521800D01*
X521900Y771350D01*
G01X531600Y770200D02*
X530350Y771450D01*
G01D02*
X527000D01*
G01X514000Y795750D02*
Y793500D01*
X515000Y792500D01*
G01X530000Y795750D02*
Y794500D01*
X532000Y792500D01*
G01X535178Y788181D02*
X532000Y791359D01*
Y792500D01*
G01X519069Y788717D02*
X518864Y788922D01*
X515899D01*
X515000Y789821D01*
Y792500D01*
G01X512679Y824100D02*
X508579D01*
G01X516906Y824148D02*
X524906D01*
G01X516906D02*
X516858Y824100D01*
X512679D01*
G01X524906Y824148D02*
X528906D01*
G01X535827Y889470D02*
Y880373D01*
X538000Y878200D01*
G01X557616Y-3517D02*
Y-315D01*
G01X554414D02*
X557616D01*
G01D02*
X560818D01*
G01X560633Y127988D02*
X563002Y130357D01*
Y133845D01*
G01X559591D02*
Y129030D01*
X560633Y127988D01*
G01X551750Y134094D02*
Y137518D01*
X551730Y137538D01*
G01X552800Y140800D02*
X551730Y139730D01*
Y137538D01*
G01X563002Y137345D02*
Y140482D01*
X562603Y140881D01*
G01X559591Y137345D02*
X563002D01*
G01X555230Y137538D02*
X559398D01*
X559591Y137345D01*
G01X555250Y134094D02*
Y137518D01*
X555230Y137538D01*
G01X569500Y240225D02*
X570389D01*
X573434Y243270D01*
G01X542800Y809050D02*
Y806300D01*
X542500Y806000D01*
G01X570473Y889470D02*
Y879851D01*
X568898Y878276D01*
G01X561024Y889470D02*
Y879850D01*
X562598Y878276D01*
G01X557874Y889470D02*
Y879850D01*
X556300Y878276D01*
G01X548426Y889470D02*
Y879850D01*
X550000Y878276D01*
G01X545276Y889470D02*
Y879476D01*
X544000Y878200D01*
G01X600923Y-3517D02*
Y-315D01*
G01X597721D02*
X600923D01*
G01D02*
X604125D01*
G01X593636Y130318D02*
Y128056D01*
X591377Y125797D01*
G01X597044Y130318D02*
Y126425D01*
X597846Y125623D01*
G01X600522Y130303D02*
Y127623D01*
X598522Y125623D01*
X597846D01*
G01X603924Y130303D02*
Y128398D01*
X605924Y126398D01*
G01X600522Y133803D02*
X603924D01*
G01X597044Y133818D02*
X600507D01*
X600522Y133803D01*
G01X597044Y133818D02*
X593636D01*
G01X603924Y133803D02*
X605805D01*
X608089Y131519D01*
G01X588363Y220858D02*
X584363D01*
G01X592363D02*
X588363D01*
G01X603163D02*
X603318Y221013D01*
X608413D01*
X608800Y221400D01*
G01X592363Y220858D02*
X592518Y221013D01*
X597658D01*
X597813Y220858D01*
G01D02*
X597968Y221013D01*
X602938D01*
X603093Y220858D01*
X603163D01*
G01X582363Y229808D02*
Y230063D01*
X587100Y234800D01*
G01X609000Y390350D02*
Y367508D01*
X606719Y365227D01*
Y356400D01*
X609000Y354119D01*
Y347700D01*
X600800Y339500D01*
Y337400D01*
G01X598819Y889470D02*
Y879850D01*
X600393Y878276D01*
G01X595670Y889470D02*
Y879851D01*
X594095Y878276D01*
G01X586221Y889470D02*
Y879850D01*
X587795Y878276D01*
G01X583071Y889470D02*
Y879850D01*
X581497Y878276D01*
G01X573623Y889470D02*
Y879850D01*
X575197Y878276D01*
G01X619100Y418000D02*
X620600D01*
X673500Y365100D01*
Y328000D01*
X661500Y316000D01*
Y282671D01*
X669463Y274708D01*
G01X633465Y889470D02*
Y879851D01*
X631890Y878276D01*
G01X624016Y889470D02*
Y879850D01*
X625590Y878276D01*
G01X620867Y889470D02*
Y879851D01*
X619292Y878276D01*
G01X611418Y889470D02*
Y879850D01*
X612992Y878276D01*
G01X608268Y889470D02*
Y879851D01*
X606693Y878276D01*
G01X660146Y-276199D02*
Y-356199D01*
G01X644230Y-3517D02*
Y-315D01*
G01X641028D02*
X644230D01*
G01D02*
X647432D01*
G01X669463Y274708D02*
X670063D01*
G01X652800Y788200D02*
Y786400D01*
X648900Y782500D01*
G01X671260Y889470D02*
Y879850D01*
X672834Y878276D01*
G01X668111Y889470D02*
Y879851D01*
X666536Y878276D01*
G01X658662Y889470D02*
Y879850D01*
X660236Y878276D01*
G01X655512Y889470D02*
Y879712D01*
X654000Y878200D01*
G01X646063Y889470D02*
Y881763D01*
X642200Y877900D01*
G01X687537Y-3517D02*
Y-315D01*
G01X684335D02*
X687537D01*
G01D02*
X690739D01*
G01X695000Y817300D02*
Y818500D01*
X698100Y821600D01*
G01X705906Y889470D02*
Y879851D01*
X704331Y878276D01*
G01X696457Y889470D02*
Y879850D01*
X698031Y878276D01*
G01X693308Y889470D02*
Y879851D01*
X691733Y878276D01*
G01X683859Y889470D02*
Y879850D01*
X685433Y878276D01*
G01X680709Y889470D02*
Y879851D01*
X679134Y878276D01*
G01X718800Y17920D02*
Y12109D01*
X713445Y6754D01*
X711919D01*
G01X712113Y37236D02*
X710376D01*
X709120Y35980D01*
G01X720100Y41550D02*
X722350D01*
X723100Y42300D01*
X723200D01*
G01X707051Y12174D02*
X708795Y10430D01*
X711510D01*
G01X737402Y889470D02*
Y879851D01*
X735827Y878276D01*
G01X727953Y889470D02*
Y879850D01*
X729527Y878276D01*
G01X755700Y79100D02*
X750130Y73530D01*
Y63340D01*
G01X809000Y76000D02*
X807532Y77468D01*
X779068D01*
X772000Y70400D01*
Y64200D01*
G01X743490Y111940D02*
Y110210D01*
X750800Y102900D01*
X753700D01*
G01X749800Y91400D02*
X750500Y92100D01*
Y99700D01*
X753700Y102900D01*
G01X755700Y79100D02*
X753100Y81700D01*
Y88100D01*
X749800Y91400D01*
G01X743490Y111940D02*
X746450Y114900D01*
X754800D01*
X756900Y112800D01*
X765000D01*
G01X765749Y889470D02*
Y879850D01*
X767323Y878276D01*
G01X762599Y889470D02*
Y879851D01*
X761024Y878276D01*
G01X753150Y889470D02*
Y879850D01*
X754724Y878276D01*
G01X750000Y889470D02*
Y879850D01*
X748426Y878276D01*
G01X740552Y889470D02*
Y879850D01*
X742126Y878276D01*
G01X775146Y-276199D02*
Y-356199D01*
G01X900200Y9600D02*
Y9100D01*
X885200Y-5900D01*
X798600D01*
X798061Y-6439D01*
G01X791200Y125300D02*
X795302Y121198D01*
X798202D01*
X810000Y109400D01*
G01X803544Y889470D02*
Y879850D01*
X805118Y878276D01*
G01X800394Y889470D02*
Y879851D01*
X798819Y878276D01*
G01X790945Y889470D02*
Y879850D01*
X792519Y878276D01*
G01X787796Y889470D02*
Y879851D01*
X786221Y878276D01*
G01X778347Y889470D02*
Y879850D01*
X779921Y878276D01*
G01X775197Y889470D02*
Y879850D01*
X773623Y878276D01*
G01X813900Y12900D02*
X814400Y12400D01*
Y5200D01*
X816600Y3000D01*
X845000D01*
X851100Y9100D01*
G01X843400Y52300D02*
X833700Y42600D01*
X832800D01*
X814394Y24194D01*
Y13394D01*
X813900Y12900D01*
G01X826138Y13554D02*
X824821D01*
X822812Y15563D01*
G01X820212Y14169D02*
X821418D01*
X822812Y15563D01*
G01D02*
Y20155D01*
X821877Y21090D01*
G01X826138Y13554D02*
X829556D01*
X830252Y14250D01*
G01X834252D02*
X830252D01*
G01X838252D02*
X834252D01*
G01X842252D02*
X838252D01*
G01X809000Y76000D02*
Y86900D01*
X812700Y90600D01*
X817000D01*
X819000Y92600D01*
Y97100D01*
G01D02*
X820185Y98285D01*
Y101115D01*
X812900Y108400D01*
X811000D01*
X810000Y109400D01*
G01X838189Y889470D02*
Y879850D01*
X836615Y878276D01*
G01X828741Y889470D02*
Y879850D01*
X830315Y878276D01*
G01X812993Y889470D02*
Y879851D01*
X811418Y878276D01*
G01X859300Y9900D02*
X859900D01*
X862325Y12325D01*
X864150D01*
G01X873100Y27250D02*
X876750Y23600D01*
X877500D01*
G01X864150Y20075D02*
X859125D01*
X858100Y21100D01*
Y21400D01*
G01X842252Y14250D02*
X846252D01*
G01D02*
Y9848D01*
X847000Y9100D01*
G01X871000Y78750D02*
Y78000D01*
X860917Y67917D01*
X846583D01*
X844185Y70315D01*
Y75835D01*
X852400Y84050D01*
G01X871550Y56450D02*
Y52700D01*
G01X875000Y78750D02*
X871000D01*
G01X848100Y84150D02*
X845850D01*
X844900Y85100D01*
G01X852895Y748648D02*
X856906D01*
G01X860906D02*
X864906D01*
G01X860906D02*
X856906D01*
G01X864906D02*
X868906D01*
G01X847500Y762150D02*
X844150D01*
G01X874398Y764898D02*
Y762774D01*
X875145Y762027D01*
Y759511D01*
X874887Y759253D01*
G01X862678Y762181D02*
X860397Y759900D01*
X858695D01*
G01X857500Y778250D02*
X857550D01*
G01X877898Y764898D02*
Y765802D01*
X874000Y769700D01*
Y772000D01*
G01X862678Y765681D02*
X860681D01*
X858600Y763600D01*
X858126D01*
G01X854560Y782690D02*
X851510Y785740D01*
X848660D01*
G01Y789240D02*
X851867Y789247D01*
X851890Y789270D01*
G01X865378Y801181D02*
X865411Y801148D01*
X869906D01*
G01X877949Y803710D02*
X872468D01*
X869906Y801148D01*
G01X846706Y797648D02*
X850239Y801181D01*
G01D02*
X865378D01*
G01X850788Y889470D02*
Y879851D01*
X849213Y878276D01*
G01X841339Y889470D02*
Y879850D01*
X842913Y878276D01*
G01X880883Y30583D02*
Y29483D01*
X878650Y27250D01*
X877300D01*
G01X887500Y44900D02*
Y40400D01*
X887800Y40100D01*
G01X893100Y38150D02*
X900250D01*
G01X875050Y52700D02*
Y56250D01*
G01X911000Y78750D02*
X906500D01*
G01X879500D02*
X875000D01*
G01X884000D02*
X888500D01*
G01D02*
X893000D01*
G01D02*
X897500D01*
G01D02*
X902000D01*
G01D02*
X906500D01*
G01X884000D02*
X879500D01*
G01X905650Y112500D02*
Y115886D01*
X905906Y116142D01*
G01X877200Y748550D02*
Y748500D01*
X879800Y745900D01*
X883100D01*
X885400Y743600D01*
G01X893406Y748648D02*
Y745106D01*
X893400Y745100D01*
G01X885306Y748648D02*
X889306D01*
G01X885306D02*
X881306D01*
G01X889306D02*
X893406D01*
G01X892678Y761681D02*
Y761485D01*
X895278Y758885D01*
G01X887500Y781250D02*
Y781000D01*
X889500Y779000D01*
Y770000D01*
X889900Y769600D01*
G01X892678Y765181D02*
X892628D01*
X889900Y767909D01*
Y769600D01*
G01X882049Y803710D02*
X877949D01*
G01X894406Y801148D02*
X898406D01*
G01X886276Y803758D02*
X882097D01*
X882049Y803710D01*
G01X886276Y803758D02*
X891796D01*
X894406Y801148D01*
G01X938000Y78750D02*
X933500D01*
G01X924500D02*
X929000D01*
G01D02*
X933500D01*
G01X920000D02*
X915500D01*
G01X938000D02*
X942500D01*
G01X920000D02*
X924500D01*
G01X911000D02*
X915500D01*
G01X942646Y-276199D02*
Y-356199D01*
G01X956000Y78750D02*
X956691Y79441D01*
X961890D01*
X966150Y75181D01*
Y67735D01*
X967180Y66705D01*
G01D02*
X970692D01*
X982638Y78651D01*
X1052651D01*
X1064300Y90300D01*
Y282460D01*
X1090340Y308500D01*
X1277700D01*
X1283300Y302900D01*
G01X952750Y72000D02*
X952500Y72250D01*
Y75100D01*
G01X952750Y67900D02*
X947900D01*
G01X951500Y78750D02*
X956000D01*
G01X942500D02*
X947000D01*
G01D02*
X951500D01*
G01Y93250D02*
X947000D01*
G01D02*
X942500D01*
G01X947000D02*
Y95000D01*
X949500Y97500D01*
G01X1005462Y35919D02*
Y37126D01*
X1007921Y39585D01*
G01X1008962Y35919D02*
X1009666Y35215D01*
Y30326D01*
X1010975Y29017D01*
G01X1061000Y111000D02*
Y95500D01*
X1053500Y88000D01*
X995000D01*
X990552Y92448D01*
Y101050D01*
G01X999000D02*
X1003100D01*
G01X990552D02*
X986552D01*
G01X1003100D02*
X1016500D01*
G01X1034231Y2842D02*
X1030458D01*
X1025700Y7600D01*
G01X1040121Y26870D02*
X1043295Y23696D01*
Y22184D01*
X1044161Y21318D01*
G01X1043450Y36615D02*
X1042578Y35743D01*
X1039822D01*
G01X1033875Y57650D02*
Y53942D01*
X1035783Y52034D01*
Y51473D01*
G01X1039500Y50500D02*
X1036756D01*
X1035783Y51473D01*
G01X1017096Y57597D02*
X1016923D01*
X1014700Y55374D01*
Y53700D01*
G01X1016500Y101050D02*
X1051050D01*
X1053000Y103000D01*
Y109500D01*
G01X1041339Y889470D02*
Y879851D01*
X1039764Y878276D01*
G01X1031890Y889470D02*
Y879850D01*
X1033464Y878276D01*
G01X1049161Y8357D02*
X1047979D01*
X1045850Y6228D01*
G01X1052162Y18357D02*
X1052201Y18396D01*
X1056049D01*
G01X1044147Y13840D02*
X1046040D01*
X1047429Y15229D01*
G01X1065475Y40823D02*
X1062314D01*
X1062088Y40597D01*
G01X1054950Y36615D02*
X1058070D01*
X1062052Y40597D01*
X1062088D01*
G01X1065475Y52323D02*
X1065525Y52273D01*
X1070415D01*
X1070924Y52782D01*
X1073712D01*
X1077432Y56502D01*
Y64225D01*
G01X1050875Y61090D02*
X1051385Y61600D01*
X1057998D01*
X1061342Y64944D01*
G01Y75846D02*
X1059912Y77276D01*
X1057259D01*
G01X1069686Y889470D02*
Y879850D01*
X1071260Y878276D01*
G01X1053937Y889470D02*
Y879850D01*
X1052363Y878276D01*
G01X1044489Y889470D02*
Y879850D01*
X1046063Y878276D01*
G01X1107481Y889470D02*
Y879850D01*
X1109055Y878276D01*
G01X1104331Y889470D02*
Y879851D01*
X1102756Y878276D01*
G01X1094882Y889470D02*
Y879850D01*
X1096456Y878276D01*
G01X1091733Y889470D02*
Y879851D01*
X1090158Y878276D01*
G01X1082284Y889470D02*
Y879850D01*
X1083858Y878276D01*
G01X1079134Y889470D02*
Y879850D01*
X1077560Y878276D01*
G01X1112646Y-276199D02*
Y-356199D01*
G01X1116671Y-3517D02*
Y-315D01*
G01D02*
Y2887D01*
G01X1113469Y-315D02*
X1116671D01*
G01D02*
X1119873D01*
G01X1142126Y889470D02*
Y879850D01*
X1140552Y878276D01*
G01X1132678Y889470D02*
Y879850D01*
X1134252Y878276D01*
G01X1129528Y889470D02*
Y879851D01*
X1127953Y878276D01*
G01X1120079Y889470D02*
Y879850D01*
X1121653Y878276D01*
G01X1116930Y889470D02*
Y879851D01*
X1115355Y878276D01*
G01X1159978Y-3517D02*
Y-315D01*
G01D02*
Y2887D01*
G01X1156776Y-315D02*
X1159978D01*
G01D02*
X1163180D01*
G01X1168207Y139776D02*
Y141907D01*
X1170400Y144100D01*
G01X1171622Y139778D02*
X1168209D01*
X1168207Y139776D01*
G01X1178558Y138068D02*
X1175157D01*
X1175156Y138069D01*
G01D02*
X1174131D01*
X1172422Y139778D01*
X1171622D01*
G01X1162607Y823010D02*
Y819407D01*
X1161700Y818500D01*
G01X1167323Y889470D02*
Y879851D01*
X1165748Y878276D01*
G01X1157874Y889470D02*
Y879850D01*
X1159448Y878276D01*
G01X1154725Y889470D02*
Y879851D01*
X1153150Y878276D01*
G01X1145276Y889470D02*
Y879850D01*
X1146850Y878276D01*
G01X1203285Y-3517D02*
Y-315D01*
G01D02*
Y2887D01*
G01X1200083Y-315D02*
X1203285D01*
G01D02*
X1206487D01*
G01X1214795Y142443D02*
Y140335D01*
X1209400Y134940D01*
X1207745D01*
G01X1204335Y134941D02*
X1207744D01*
X1207745Y134940D01*
G01X1201969Y889470D02*
Y879851D01*
X1200394Y878276D01*
G01X1192520Y889470D02*
Y879850D01*
X1194094Y878276D01*
G01X1189371Y889470D02*
Y879851D01*
X1187796Y878276D01*
G01X1179922Y889470D02*
Y879850D01*
X1181496Y878276D01*
G01X1243390Y-315D02*
X1246592D01*
G01X1237308Y150303D02*
X1240709D01*
G01D02*
X1242621Y152215D01*
Y153690D01*
G01X1246063Y889470D02*
Y879850D01*
X1244489Y878276D01*
G01X1236615Y889470D02*
Y879850D01*
X1238189Y878276D01*
G01X1233465Y889470D02*
Y879851D01*
X1231890Y878276D01*
G01X1224016Y889470D02*
Y879850D01*
X1225590Y878276D01*
G01X1246592Y-3517D02*
Y-315D01*
G01D02*
Y2887D01*
G01Y-315D02*
X1249794D01*
G01X1274410Y889470D02*
Y879850D01*
X1275984Y878276D01*
G01X1271260Y889470D02*
Y879850D01*
X1269686Y878276D01*
G01X1261812Y889470D02*
Y879850D01*
X1263386Y878276D01*
G01X1258662Y889470D02*
Y879851D01*
X1257087Y878276D01*
G01X1249213Y889470D02*
Y879850D01*
X1250787Y878276D01*
G01X1310146Y-276199D02*
Y-356199D01*
G01X1342146Y-260199D02*
X1310146D01*
G01X1289899Y-3517D02*
Y-315D01*
G01D02*
Y2887D01*
G01X1286697Y-315D02*
X1289899D01*
G01D02*
X1293101D01*
G01X1304000Y44000D02*
Y24700D01*
X1303983Y24683D01*
Y22083D01*
G01X1304000Y90500D02*
Y67500D01*
G01D02*
X1304860Y66640D01*
Y44860D01*
X1304000Y44000D01*
G01X1303700Y289500D02*
X1303800Y289400D01*
X1325500D01*
G01X1314128Y677117D02*
X1310128D01*
G01X1306128D02*
X1302128D01*
G01X1297617D02*
X1302128D01*
G01X1306128D02*
X1310128D01*
G01X1307400Y690150D02*
X1307431D01*
X1310376Y687205D01*
G01X1306000Y713250D02*
X1303950Y711200D01*
X1301728D01*
G01X1307400Y693650D02*
X1304500Y696550D01*
Y698000D01*
G01X1306000Y716750D02*
X1303850D01*
Y716722D01*
X1301728Y714600D01*
G01X1302000Y703250D02*
Y700500D01*
X1304500Y698000D01*
G01X1314628Y729617D02*
X1310133D01*
X1310100Y729650D01*
G01X1291428Y726117D02*
X1294961Y729650D01*
X1310100D01*
G01X1312205Y889470D02*
Y879850D01*
X1313779Y878276D01*
G01X1309056Y889470D02*
Y879851D01*
X1307481Y878276D01*
G01X1287008Y889470D02*
Y879850D01*
X1288582Y878276D01*
G01X1283859Y889470D02*
Y879851D01*
X1282284Y878276D01*
G01X1296457Y889470D02*
Y880943D01*
X1299300Y878100D01*
X1301800D01*
G01X1299607Y889470D02*
Y882993D01*
X1301800Y880800D01*
Y878100D01*
G01X1338146Y-260199D02*
G02I-12000J0D01*
G01X1332996D02*
G02I-6850J0D01*
G01X1326146Y-276199D02*
Y-244199D01*
G01X1333500Y290500D02*
X1332400Y289400D01*
X1325500D01*
G01X1322128Y677117D02*
X1326128D01*
G01D02*
X1330128D01*
G01D02*
X1338128D01*
G01X1322128D02*
X1314128D01*
G01X1341400Y690150D02*
Y686900D01*
G01X1324900Y690150D02*
Y689891D01*
X1323076Y688067D01*
Y686999D01*
G01X1341400Y693650D02*
X1337500Y697550D01*
Y698000D01*
G01X1324900Y693650D02*
X1324350D01*
X1322439Y695561D01*
Y697767D01*
G01X1319500Y705750D02*
Y700706D01*
X1322439Y697767D01*
G01X1336000Y701750D02*
Y699500D01*
X1337500Y698000D01*
G01X1334128Y729617D02*
X1325633D01*
G01D02*
X1325500Y729750D01*
G01X1325633Y729617D02*
X1314628D01*
G01X1338128D02*
X1334128D01*
G01X1346851Y889470D02*
Y879851D01*
X1345276Y878276D01*
G01X1337402Y889470D02*
Y879850D01*
X1338976Y878276D01*
G01X1334252Y889470D02*
Y879850D01*
X1332678Y878276D01*
G01X1324804Y889470D02*
Y879850D01*
X1326378Y878276D01*
G01X1321654Y889470D02*
Y879851D01*
X1320079Y878276D01*
G01X1371614Y175745D02*
X1368028D01*
G01X1378500Y198000D02*
X1380200Y199700D01*
Y250600D01*
X1376300Y254500D01*
X1369300D01*
G01X1363500Y267800D02*
X1368300D01*
G01X1369300Y254500D02*
Y259300D01*
G01X1355000Y283250D02*
Y286300D01*
G01X1351000Y283250D02*
Y285400D01*
X1351900Y286300D01*
X1355000D01*
G01X1359000Y283250D02*
Y284974D01*
X1357674Y286300D01*
X1355000D01*
X18577Y107902D03*
X5500Y119571D03*
Y139571D03*
Y159571D03*
X22000Y167200D03*
X5500Y179571D03*
Y199571D03*
X26500Y199500D03*
X21900Y199700D03*
X21800Y188100D03*
X5500Y219571D03*
Y239571D03*
X23100Y224500D03*
X27300Y229000D03*
X28400Y262800D03*
X18000Y271600D03*
X5500Y259571D03*
X26600Y249217D03*
Y253582D03*
X18000Y289400D03*
X28200Y296100D03*
X5500Y279571D03*
Y299571D03*
X24000Y308700D03*
X26300Y317600D03*
X21400Y327900D03*
Y341000D03*
X5500Y339571D03*
Y319571D03*
X24639Y321239D03*
X21400Y354000D03*
X22900Y365300D03*
X5500Y359571D03*
Y399571D03*
Y379571D03*
X31324Y410800D03*
X25350Y389000D03*
X17500Y412374D03*
X20713Y410087D03*
X5500Y419571D03*
Y439571D03*
X21300Y429500D03*
X20713Y418326D03*
X5500Y479571D03*
Y459571D03*
X23720Y472640D03*
X5500Y499571D03*
Y519571D03*
Y539571D03*
X29300Y539850D03*
X24800Y540900D03*
X5500Y579571D03*
Y559571D03*
Y599571D03*
Y639571D03*
Y619571D03*
Y679571D03*
Y659571D03*
X26100Y671200D03*
X24000Y659000D03*
X29500Y676500D03*
X5500Y699571D03*
X27125Y695275D03*
X25200Y712650D03*
X17500Y706300D03*
X21300Y728400D03*
X21108Y732713D03*
X18250Y749250D03*
X5500Y719571D03*
Y739571D03*
X25050Y716900D03*
X21250Y742650D03*
X27000Y754400D03*
X5500Y779571D03*
Y759571D03*
Y799571D03*
X10020Y835051D03*
X30020D03*
X5500Y819571D03*
X31400Y209190D03*
X46760Y209157D03*
X63250Y205050D03*
X42800Y200100D03*
X44400Y216600D03*
X34900Y216800D03*
X59800Y211800D03*
X50200Y212000D03*
X31500Y224400D03*
X41250Y216728D03*
X53400Y211928D03*
X38050Y216728D03*
X56600Y211928D03*
X58400Y271800D03*
X57500Y263300D03*
X63700Y257300D03*
X63800Y267100D03*
X44029Y272572D03*
X44426Y267408D03*
X35150Y273250D03*
X60872Y274328D03*
X63700Y260725D03*
X55800Y266293D03*
X63700Y263925D03*
X55800Y269493D03*
X44900Y261750D03*
X35300Y303100D03*
X59173Y288186D03*
X42900Y284500D03*
X58730Y299508D03*
X35150Y284350D03*
X47912Y294940D03*
X39000Y299500D03*
X53100Y279500D03*
X47800Y309400D03*
X31662Y303262D03*
X58700Y308600D03*
X61800Y306900D03*
X38800Y302900D03*
X62200Y288256D03*
X58383Y294947D03*
X47355Y303376D03*
X47991Y299958D03*
X49934Y280811D03*
X49100Y328300D03*
X39600Y317600D03*
X58990Y342700D03*
X34800Y321200D03*
X54600Y328600D03*
X38500Y321400D03*
X58100Y334600D03*
X62400Y334500D03*
X31700Y314700D03*
X52050Y316100D03*
X51050Y321650D03*
X62400Y342700D03*
X38518Y376916D03*
X34153D03*
X39866Y371366D03*
X52521Y350357D03*
X31500Y366900D03*
X48512Y356488D03*
X49300Y346700D03*
X43262Y357062D03*
X44866Y378634D03*
X55907Y350673D03*
X54200Y347400D03*
X62838Y392392D03*
X60610Y381665D03*
X39300Y389557D03*
X47132Y444399D03*
X48000Y426000D03*
Y422500D03*
Y429500D03*
X57800Y420700D03*
X35709Y426942D03*
X43500Y418802D03*
X47734Y465792D03*
X45531Y474400D03*
X31500Y447000D03*
X64820Y455887D03*
X64680Y452389D03*
X64500Y459400D03*
X36750Y462900D03*
X53200Y462500D03*
X49812Y479921D03*
X33900Y469300D03*
X46500Y460300D03*
X46087Y455819D03*
X50140Y494559D03*
X60987Y489223D03*
X63519Y505320D03*
X62298Y484200D03*
X35700Y488500D03*
X60150Y506450D03*
X50140Y490750D03*
X60900Y495122D03*
X61870Y515670D03*
X60300Y533900D03*
X61128Y519646D03*
X64200Y534500D03*
X61800Y537000D03*
X55950Y564500D03*
Y572500D03*
X63000Y558930D03*
X62611Y608289D03*
X62400Y624500D03*
X53000Y645000D03*
X63300Y634800D03*
X43600Y665700D03*
X54200Y666800D03*
X60700Y682100D03*
X47800Y666400D03*
X35766Y673178D03*
X34500Y666500D03*
X39900Y678100D03*
X33600Y675800D03*
X43100Y670900D03*
X36624Y669155D03*
X47300Y704400D03*
X42300Y704900D03*
X62000Y713000D03*
X45800Y685100D03*
X42100Y684000D03*
X53500Y690200D03*
X60650Y694050D03*
X63300Y697200D03*
X59100Y705600D03*
X42130Y694440D03*
X38000Y684000D03*
X59300Y734900D03*
X54300Y729900D03*
X49300Y734900D03*
X54300Y739900D03*
Y734900D03*
X56590Y720410D03*
X47800Y772900D03*
X35000Y769900D03*
X39000D03*
X42800Y770000D03*
X52500Y779600D03*
X64900Y780500D03*
X50020Y835051D03*
X96584Y195100D03*
X78050Y196300D03*
X82676Y208785D03*
X67600Y209500D03*
X92859Y226659D03*
X87978Y226596D03*
X78508Y232693D03*
X72934Y232675D03*
X95200Y210800D03*
X85600D03*
X80600Y216700D03*
X71000Y216600D03*
X88276Y232700D03*
X88259Y223184D03*
X92659D03*
X78000Y229289D03*
X73600D03*
X77400Y216528D03*
X88800Y210851D03*
X74200Y216528D03*
X92000Y210851D03*
X97480Y266420D03*
X94600Y277100D03*
X93672Y270153D03*
X71870Y257120D03*
X77527Y255800D03*
X94530Y264671D03*
X75800Y274100D03*
X68100Y255000D03*
X71094Y285981D03*
X77964Y285670D03*
X68429Y288212D03*
X75400Y309700D03*
X71500Y297900D03*
X77100Y303800D03*
X65400D03*
X65500Y291900D03*
X77500D03*
X89400Y279300D03*
X96798Y301484D03*
Y297915D03*
X95700Y293900D03*
X73125Y288231D03*
X76325D03*
X65400Y288256D03*
X84600Y303000D03*
X78121Y325870D03*
X73721D03*
X70210Y342700D03*
X77290Y344212D03*
X86511Y344200D03*
X66400Y334500D03*
X66800Y342700D03*
X83500Y344200D03*
X80300D03*
X77421Y322470D03*
X74221D03*
X79455Y357174D03*
X75256Y370303D03*
X70591Y359309D03*
X71794Y377639D03*
X76055Y357145D03*
X82500Y362890D03*
X92580Y410761D03*
X79600Y399200D03*
X95223Y385704D03*
X79267Y410185D03*
X80940Y395989D03*
X86904Y385798D03*
X72708Y382055D03*
X68365Y381464D03*
X84700Y396000D03*
X92752Y434193D03*
X91370Y445394D03*
X70700Y443244D03*
X77859Y429879D03*
X72533Y416996D03*
X79164Y426221D03*
X96351Y443000D03*
Y438600D03*
X85042Y439144D03*
X91200Y448800D03*
Y453200D03*
X91311Y456609D03*
X89400Y470400D03*
X89500Y466600D03*
X85748Y475813D03*
X73232Y476912D03*
X97100Y466500D03*
X98400Y454400D03*
X77681Y499033D03*
X77413Y506468D03*
X76100Y483400D03*
X77700Y502500D03*
X88573Y503935D03*
X70910Y502219D03*
X67700Y499120D03*
X77700Y522500D03*
X88204Y543283D03*
X89200Y518700D03*
Y528500D03*
X65600Y543200D03*
X75600Y518600D03*
X67700Y518500D03*
X67162Y515142D03*
X77300Y531238D03*
X77700Y538500D03*
X74301Y538390D03*
X65800Y538900D03*
X74300Y533600D03*
X73900Y527050D03*
X77372Y526885D03*
X73700Y542600D03*
X70000Y542500D03*
X74000Y557000D03*
X77500Y554500D03*
X90500Y580100D03*
X81000Y579000D03*
X95252Y571638D03*
X70800Y559895D03*
X77400Y559000D03*
X77250Y562750D03*
X77400Y577000D03*
X71400Y578300D03*
X87555Y561085D03*
X87200Y574250D03*
X87337Y569268D03*
X84226Y577924D03*
X87200Y565785D03*
X77400Y550400D03*
X65381Y548719D03*
X87608Y557685D03*
X69100Y549200D03*
X73700Y549300D03*
X92000Y591200D03*
X69500Y586000D03*
X90500Y587000D03*
X80300Y596100D03*
X69258Y603000D03*
X82000Y592500D03*
X66000Y604800D03*
X88000Y613600D03*
X81000Y589000D03*
X78300Y634250D03*
X94860Y628750D03*
X78300Y637750D03*
X75800Y681900D03*
X94950Y677850D03*
X75450Y694150D03*
X69700Y690300D03*
X89825Y692875D03*
X79250Y716050D03*
X91800Y716100D03*
X66700Y713500D03*
X74500Y713400D03*
X91450Y707650D03*
X65350Y690356D03*
X89400Y749200D03*
X89300Y736300D03*
X95400Y731600D03*
Y728200D03*
X68900Y730000D03*
X68465Y736229D03*
X85800Y727500D03*
Y731000D03*
X74300Y769950D03*
X89800Y753400D03*
X69800Y772700D03*
X86900Y757900D03*
X89400Y762400D03*
X93100Y813200D03*
X70020Y835051D03*
X90020D03*
X93300Y818900D03*
X118577Y107902D03*
X104000Y128330D03*
X114364Y122054D03*
X118500Y176500D03*
Y173000D03*
X100900Y173800D03*
X108631Y168836D03*
X116000Y207000D03*
Y202000D03*
X118500Y188500D03*
X116000Y192000D03*
Y196500D03*
X118500Y185000D03*
Y181000D03*
X104100Y194600D03*
X103700Y200800D03*
X111967Y199632D03*
X119800Y234531D03*
X116000Y211500D03*
X103100Y211600D03*
X127330Y248029D03*
X112764Y264218D03*
X109600Y276850D03*
X112732Y272786D03*
X107340Y266140D03*
X101463Y268811D03*
X102499Y281183D03*
X109810Y310358D03*
X109972Y305968D03*
X112217Y296435D03*
X108500Y284000D03*
X107213Y301192D03*
X120700Y282400D03*
X100500Y285300D03*
X113915Y307600D03*
X117484D03*
X106400Y312200D03*
X101630Y312236D03*
X106717Y335600D03*
X117700Y323400D03*
X111900Y344200D03*
X113000Y336000D03*
X107558Y321012D03*
X122000Y343300D03*
X100277Y336077D03*
X102000Y364700D03*
X99128Y366961D03*
X108200Y378656D03*
X126800Y362500D03*
X108484Y348377D03*
X122645Y367966D03*
X117300Y361700D03*
X108453Y385164D03*
X100924Y409968D03*
X115951Y384138D03*
X111950Y392050D03*
X104204Y383661D03*
X129500Y412400D03*
X124290Y401910D03*
X125718Y383302D03*
X125600Y386700D03*
X107358Y409942D03*
X126122Y432323D03*
X105303Y419497D03*
X116173Y422379D03*
X107844Y414785D03*
X99749Y443671D03*
X99818Y437908D03*
X127925Y428093D03*
X116235Y444665D03*
X103179Y423267D03*
X103176Y434180D03*
X110406Y417067D03*
X113518Y420179D03*
X131304Y418855D03*
X131004Y422710D03*
X130633Y444763D03*
X120200Y436400D03*
X115500Y454700D03*
X111500D03*
X103500D03*
X120000Y451285D03*
X107900Y448900D03*
X101200Y470400D03*
X129520Y448660D03*
X127820Y452280D03*
X123696Y454452D03*
X114400Y550000D03*
X104461Y571715D03*
X100140Y559260D03*
X99460Y566200D03*
X102870Y565740D03*
Y561340D03*
X105851Y611436D03*
X104400Y590300D03*
X102000Y599000D03*
Y602500D03*
X101750Y595600D03*
X120351Y633500D03*
X126851Y633449D03*
X116551Y644936D03*
X128220Y620392D03*
X125581Y641436D03*
X109051Y645936D03*
X131051Y656436D03*
X119051Y653906D03*
X109800Y681900D03*
X130900Y714300D03*
Y710800D03*
X107950Y687650D03*
X124150Y707050D03*
X111400Y741800D03*
Y718300D03*
X118060Y743460D03*
X106900Y738600D03*
Y721300D03*
X115000Y717600D03*
X107000Y717800D03*
X132200Y761300D03*
Y756300D03*
X111300Y756000D03*
X109900Y828800D03*
X105400Y828700D03*
X103200Y825400D03*
X115500Y825500D03*
X107600D03*
X120000Y843500D03*
X126500Y878200D03*
Y871000D03*
X129000Y875000D03*
X117500Y878200D03*
X122000D03*
X124500Y875000D03*
X120000Y865000D03*
Y875000D03*
Y853500D03*
X138577Y107902D03*
X158577D03*
X149380Y176010D03*
X162500Y173500D03*
X163000Y211500D03*
X157200Y241400D03*
X153000Y225000D03*
X155026Y212580D03*
X134120Y267630D03*
X157300Y259900D03*
X157400Y254000D03*
X157300Y246500D03*
X155662Y266438D03*
X159662Y266600D03*
X162910Y244290D03*
X139286Y311214D03*
X166087Y304350D03*
X143000Y342900D03*
X155891Y339730D03*
X134800Y329600D03*
X144595Y312861D03*
X137862Y361723D03*
X161311Y371428D03*
X141216Y361163D03*
X145027D03*
X156573Y371799D03*
X140500Y390500D03*
X145500Y385500D03*
X158800Y406255D03*
X143000Y388000D03*
X142608Y403594D03*
X157550Y399100D03*
X146105Y403610D03*
X155657Y384291D03*
X137000Y436700D03*
X145901Y441262D03*
X139019Y443177D03*
X159540Y445692D03*
X146165Y444876D03*
X149838Y446190D03*
X150431Y420306D03*
X153100Y439000D03*
X136500Y417400D03*
X152978Y435602D03*
X137344Y446737D03*
X137000Y451300D03*
X163440Y453020D03*
X133000Y454700D03*
X143547Y477976D03*
X137000Y454700D03*
X159239Y449079D03*
X159082Y452509D03*
X165851Y630651D03*
X137551Y629849D03*
X149851Y631251D03*
X155851Y631051D03*
X160851Y630651D03*
X150069Y640500D03*
X150280Y636620D03*
X150600Y648300D03*
X150409Y643884D03*
X153019Y622720D03*
X159716Y620392D03*
X166015D03*
X136651Y653036D03*
X162100Y677800D03*
X164400Y668300D03*
X160500Y689500D03*
X150000Y701500D03*
X142500Y709000D03*
X137000Y715500D03*
X164500Y693500D03*
X144400Y731600D03*
Y728200D03*
X136400Y738300D03*
Y721800D03*
X161200Y723900D03*
X150200Y729400D03*
X153700D03*
X157700Y748900D03*
X150450Y744150D03*
X146450Y736150D03*
X135700Y745200D03*
X163800Y771000D03*
X160400D03*
X154000Y779000D03*
X160700Y753400D03*
X143000Y784500D03*
X146500D03*
X150500Y804000D03*
X139250Y791250D03*
X143250Y799250D03*
X153500Y808500D03*
X163800Y820000D03*
X160400D03*
X138500Y835000D03*
X137600Y839500D03*
X141100Y824500D03*
X141000Y830700D03*
X145900Y824400D03*
X142500Y862500D03*
Y867500D03*
Y872500D03*
X138500Y869500D03*
Y875200D03*
X141000Y877700D03*
X145500D03*
X149700D03*
X142500Y856500D03*
X159449Y878276D03*
X178577Y107902D03*
X181738Y122711D03*
X171500Y207500D03*
Y202500D03*
X193400Y192900D03*
X191800Y189600D03*
X196018Y204200D03*
X167000Y211500D03*
X172450Y211050D03*
X183400Y221600D03*
X171100Y247500D03*
X191000Y246500D03*
X167600Y247600D03*
X193303Y264310D03*
X167700Y296882D03*
Y292517D03*
X180850Y285650D03*
X170062Y304556D03*
X174943Y321015D03*
X167687Y329434D03*
X192407Y320262D03*
X180571Y327023D03*
X176674Y344934D03*
X189365Y329905D03*
X179381Y369903D03*
X196529Y352284D03*
X185970Y358962D03*
X195940Y348814D03*
X182969Y352641D03*
X192150Y406429D03*
X197000Y404000D03*
X171434Y398093D03*
X177550Y407850D03*
X166321Y388316D03*
X176098Y444355D03*
X197850Y437450D03*
X185000Y419900D03*
X197531Y451187D03*
X189381Y451394D03*
X193718D03*
X196239Y462262D03*
X173471Y454700D03*
X175912Y450747D03*
X166534Y450821D03*
X186675Y453505D03*
X177500Y454300D03*
X199900Y544500D03*
X196782Y563564D03*
X197334Y567232D03*
X197500Y577300D03*
X189500Y567700D03*
X185500Y577300D03*
X184189Y564504D03*
X185500Y567700D03*
X193001Y574708D03*
X181000Y585000D03*
Y581500D03*
X198600Y599750D03*
Y588750D03*
X181371Y601636D03*
X181000Y595200D03*
X168769Y622720D03*
X171300Y678300D03*
X175200Y678500D03*
X199900Y692000D03*
X171000Y715900D03*
X167600D03*
X193500Y700000D03*
X182500Y705500D03*
X186000D03*
X178750Y712250D03*
X189000Y684500D03*
X185000D03*
X167000Y686500D03*
X199900Y747500D03*
Y741000D03*
X190000Y725000D03*
X177700Y723900D03*
X182860Y742240D03*
X181200Y748900D03*
X184700Y729400D03*
X182750Y720250D03*
X193000Y729500D03*
X171000Y764900D03*
X167600D03*
X190000Y780500D03*
X170500Y779000D03*
X193500Y755500D03*
X182500Y761000D03*
X186000D03*
X182750Y775750D03*
X178000Y753400D03*
X178750Y767750D03*
X199900Y796500D03*
X175660Y797340D03*
X174000Y804000D03*
X177500Y784500D03*
X170800Y808500D03*
X193000Y785000D03*
X195000Y824090D03*
X188572Y832186D03*
X196474Y832178D03*
X197420Y821701D03*
X194120Y830301D03*
X190920D03*
X176900Y867600D03*
X173500D03*
X196000Y868700D03*
X176771Y878276D03*
X195669D03*
X168898Y878200D03*
X185500D03*
X197218Y871676D03*
X227669Y5500D03*
X210028Y12605D03*
Y32605D03*
Y52605D03*
Y72605D03*
X226533Y72591D03*
X228121Y63589D03*
X228163Y68589D03*
X210028Y92605D03*
X227989Y83589D03*
X222354Y103006D03*
X228163Y78589D03*
X227606Y98642D03*
X223641Y99302D03*
X228163Y93589D03*
Y88589D03*
X228500Y138100D03*
X223750Y141370D03*
X218725Y138175D03*
X228007Y123787D03*
X233500Y137000D03*
X220300Y129300D03*
X222356Y133438D03*
X228708Y127115D03*
X215136Y142786D03*
X218299Y123319D03*
X224576Y116678D03*
X221418Y109634D03*
X210478Y151203D03*
X233537Y160630D03*
X213282Y188452D03*
X202892Y188441D03*
X205013Y192596D03*
X210484Y179525D03*
X206297Y188492D03*
X209866D03*
X214794Y212100D03*
X206200Y247500D03*
X209200Y252800D03*
X230400Y283400D03*
X222200Y300500D03*
X205840Y325381D03*
X210177D03*
X218102Y334880D03*
X218070Y340244D03*
X221460Y335475D03*
Y339875D03*
X228100Y364600D03*
X219018Y378000D03*
X223383D03*
X217000Y360000D03*
X219580Y356970D03*
X214776Y352807D03*
X212536Y349805D03*
X205750Y408250D03*
X205915Y422424D03*
X217190Y428485D03*
X212200Y428800D03*
X212000Y438713D03*
X217500Y441992D03*
X205200Y442900D03*
X220897Y441833D03*
X220800Y446000D03*
X200100Y415100D03*
X201868Y451187D03*
X227700Y476537D03*
Y472200D03*
X216404Y469751D03*
X216282Y463288D03*
X219763Y472187D03*
X230572Y455128D03*
X228900Y446800D03*
X219300Y508700D03*
X228298Y488100D03*
X228347Y484700D03*
X219700Y489800D03*
X202700Y495400D03*
X206700Y498000D03*
X216600Y496550D03*
X217800Y512500D03*
X200917Y490578D03*
X203550Y484522D03*
X233290Y493277D03*
X206700Y494000D03*
X203500Y499200D03*
X207026Y483956D03*
X219800Y493700D03*
X218906Y483186D03*
X226300Y505700D03*
X226530Y502307D03*
X216873Y516458D03*
X203300Y538500D03*
X206700Y544500D03*
Y538500D03*
X221000Y541300D03*
X217500Y519800D03*
Y529250D03*
X225000Y541300D03*
X229200Y514800D03*
X216300Y546350D03*
X203300Y544500D03*
Y548500D03*
X219700Y550500D03*
X218780Y560082D03*
X206700Y548500D03*
X216300Y550500D03*
X216278Y567341D03*
X202300Y559763D03*
X222300Y577300D03*
X216563Y555908D03*
X229800Y558500D03*
X206700Y554500D03*
X203304Y554684D03*
X205700Y559763D03*
X222500Y573220D03*
X216241Y563095D03*
X216090Y593937D03*
X227500Y603500D03*
X201000Y674000D03*
X206952Y655370D03*
X203300Y692000D03*
X219000Y694000D03*
X210000Y700000D03*
X231500Y699000D03*
X217000Y705500D03*
X203300Y747500D03*
Y741000D03*
X213500Y725000D03*
X215160Y718340D03*
X210300Y729500D03*
X227409Y775903D03*
X233000D03*
X213500Y780500D03*
X210000Y755500D03*
X215160Y773840D03*
X217000Y761000D03*
X228550Y772700D03*
X231750D03*
X203300Y796500D03*
X210300Y785000D03*
X203124Y824090D03*
X233650Y827374D03*
X208700Y828000D03*
X201641Y827947D03*
X214380Y827374D03*
X221052D03*
X226978D03*
X200620Y821701D03*
X231915Y830301D03*
X219317D03*
X206718D03*
X228715D03*
X216117D03*
X203518D03*
X201500Y868700D03*
X233464Y878276D03*
X208267D03*
X201969D03*
X220866D03*
X214567D03*
X227166D03*
X225615Y875176D03*
X213017D03*
X200418Y871676D03*
X222415Y875176D03*
X209817D03*
X247669Y5500D03*
X258159Y73589D03*
X257851Y63589D03*
X257759Y68589D03*
X257769Y83589D03*
X264817Y105350D03*
X257731Y78589D03*
X258100Y93589D03*
X257912Y101408D03*
X258029Y97353D03*
X260562Y85988D03*
X254000Y131500D03*
X264500Y142750D03*
X254500D03*
X246500Y139000D03*
X243000D03*
X258068Y110180D03*
X259331Y118580D03*
X264443Y109587D03*
X257422Y121792D03*
X259500Y143250D03*
Y147750D03*
Y160750D03*
Y156250D03*
X264397Y160977D03*
X264500Y157250D03*
Y153750D03*
Y150250D03*
Y146250D03*
X259500Y152000D03*
X254500Y161250D03*
Y157250D03*
Y153750D03*
Y150250D03*
Y146250D03*
X239600Y142900D03*
X243618Y143381D03*
X243500Y147500D03*
X241231Y238869D03*
X236300Y227280D03*
X247500Y233750D03*
X244300Y226700D03*
X266500Y239400D03*
X245400Y296500D03*
X267300Y300600D03*
Y328640D03*
X257340Y338640D03*
X248160Y343140D03*
X267300Y362200D03*
X244000Y377617D03*
X260929Y345571D03*
X248930Y358000D03*
X244000Y381982D03*
X258500Y391200D03*
X239100Y399200D03*
X251700Y421600D03*
Y425200D03*
X238400Y416200D03*
X235750Y419500D03*
X262900Y438700D03*
X246375Y440725D03*
X265100Y443300D03*
X264100Y425400D03*
X249342Y439064D03*
X251800Y470100D03*
X248500Y465000D03*
X263700Y474600D03*
X257493Y456679D03*
X253302D03*
X257400Y477300D03*
X235850Y455050D03*
X246300Y478600D03*
Y485400D03*
X246407Y488799D03*
X256300Y494500D03*
X244100Y499900D03*
X246800Y496800D03*
X257400Y481637D03*
X256300Y486000D03*
Y490000D03*
X260646Y499181D03*
X256855Y499154D03*
X265019Y497483D03*
X255487Y512454D03*
X242800Y495486D03*
X246500Y493400D03*
X240450Y499400D03*
X236737Y493170D03*
X243200Y508000D03*
X250200Y506600D03*
X264522Y511690D03*
X260407Y502674D03*
X257207D03*
X246300Y482000D03*
X239139Y525077D03*
X239321Y521081D03*
X249700Y525737D03*
Y521250D03*
X264500Y521309D03*
X261100Y521250D03*
X250100Y537100D03*
X236100Y517100D03*
X263300Y526300D03*
X234777Y550569D03*
X252238Y574238D03*
X255738D03*
X253500Y590500D03*
X257413D03*
X266100Y614400D03*
X265850Y606400D03*
X248500Y583000D03*
X260100Y647400D03*
X259300Y632400D03*
Y639300D03*
X250500Y642500D03*
X265900Y622400D03*
X238100Y643400D03*
X247717Y633233D03*
X259300Y635900D03*
X236000Y656000D03*
X256600Y652200D03*
X241000Y712500D03*
X262628Y744470D03*
X266980Y723854D03*
X241000Y721500D03*
X258100Y726100D03*
X241000Y725500D03*
Y718000D03*
X266906Y775531D03*
X263181Y772181D03*
X249025Y827374D03*
X255697D03*
X261624D03*
X266561Y830301D03*
X253962D03*
X263361D03*
X250762D03*
X261811Y878276D03*
X249212D03*
X239764D03*
X255511D03*
X260261Y875176D03*
X238213D03*
X257061D03*
X235013D03*
X267669Y5500D03*
X290000Y141100D03*
X274250Y133750D03*
X292000Y130000D03*
X285500D03*
X284440Y139580D03*
X285250Y133750D03*
X294500Y152500D03*
X286000Y143800D03*
X286100Y153900D03*
X280000D03*
X290500Y152500D03*
X275000Y147500D03*
X277800Y208500D03*
X271231Y237031D03*
X283622Y226340D03*
X279257D03*
X269849Y308414D03*
X277300Y304800D03*
X297090Y311350D03*
X282700Y300100D03*
X299600Y297662D03*
X269270Y315759D03*
X287200Y326802D03*
X287800Y311600D03*
X267979Y342500D03*
X295400Y325390D03*
X283700Y322100D03*
X297729Y362571D03*
X288270Y365240D03*
X297729Y351029D03*
X294009Y363063D03*
X293800Y436100D03*
X301170Y462780D03*
X301162Y459290D03*
X273783Y476100D03*
X283400Y477900D03*
X284200Y465000D03*
X275900Y467300D03*
X285800Y460810D03*
X290838Y501600D03*
X286181Y498546D03*
X291500Y497700D03*
X269000Y504962D03*
X275286Y504392D03*
X280749Y512744D03*
X286169Y502000D03*
X285776Y489300D03*
X272860Y489147D03*
X282400Y487300D03*
X295876Y520800D03*
X296200Y566900D03*
X290000Y578165D03*
X300835D03*
X279994Y554794D03*
X283600Y551400D03*
X291000Y561450D03*
X280200Y551400D03*
X289835Y583165D03*
Y588165D03*
X269000Y589000D03*
X269335Y593165D03*
X300835Y583165D03*
X301000Y588665D03*
X288835Y593165D03*
X297750Y592750D03*
X276300Y617350D03*
X281700Y634900D03*
X281800Y638900D03*
X288400Y626100D03*
Y634200D03*
X292500Y630200D03*
X271500Y639500D03*
X281100Y651700D03*
X285500Y704900D03*
X298406Y706000D03*
X290338Y715800D03*
X278406Y716531D03*
X274406Y716598D03*
X270000Y732650D03*
X283161Y730092D03*
X281500Y748500D03*
X275609Y726886D03*
X270556Y716702D03*
X269500Y736150D03*
X286500Y740500D03*
X287278Y729031D03*
X286406Y716531D03*
X296132Y726171D03*
X290720Y726333D03*
X285333Y726241D03*
X282406Y716598D03*
X298620Y728596D03*
X282378Y775431D03*
X298500Y752000D03*
X272116Y755592D03*
X298400Y775700D03*
X283500Y765631D03*
X268193Y755633D03*
X293692Y765571D03*
X287115Y765584D03*
X281500Y752000D03*
X299184Y765691D03*
X268296Y827374D03*
X280894D03*
X274222D03*
X279159Y830301D03*
X275959D03*
X286800Y863300D03*
X280800Y863500D03*
X268110Y878276D03*
X280708D03*
X287008D03*
X274410D03*
X285500Y866200D03*
X272859Y875176D03*
X282300Y866200D03*
X269659Y875176D03*
X307300Y221702D03*
X307834Y237966D03*
X306900Y251000D03*
X302500Y251600D03*
X311882Y310550D03*
X306800Y290500D03*
X328842Y300042D03*
X307425Y309838D03*
X303517Y309777D03*
X312900Y290450D03*
X321300Y301500D03*
X334200Y299600D03*
X313200Y299900D03*
X331800Y309100D03*
X310485Y314670D03*
X328800Y315900D03*
X316420Y331830D03*
X302749Y332651D03*
X326041Y329282D03*
Y325000D03*
X310839Y344339D03*
X315300Y344500D03*
X315900Y320900D03*
X313100Y371038D03*
Y374438D03*
X301320Y362500D03*
X313875Y364201D03*
X310475Y364193D03*
X316315Y369889D03*
X316205Y376006D03*
X301929Y351100D03*
X313500Y437400D03*
Y441000D03*
X313300Y429603D03*
X313294Y434006D03*
X302140Y444160D03*
X306521Y463576D03*
X304293Y466146D03*
X329014Y472022D03*
X306612Y460177D03*
X307400Y467600D03*
X303440Y475360D03*
X322268Y466591D03*
X322305Y469991D03*
X321900Y459800D03*
X322036Y463198D03*
X327512Y509612D03*
X303800Y505100D03*
X304400Y511400D03*
X327589Y504300D03*
X333102Y485902D03*
X330000Y501900D03*
X303500Y491000D03*
X305500Y483550D03*
X320500Y531000D03*
X321000Y527000D03*
X322700Y536500D03*
X311406Y535944D03*
X306900Y529100D03*
X311500Y548000D03*
X314900D03*
X322100Y638500D03*
X309000Y679000D03*
X305500Y676400D03*
X334800Y712000D03*
X302406Y706031D03*
X306406D03*
X322178Y729178D03*
X310016Y729793D03*
X312500Y716500D03*
X317300Y739300D03*
X302000Y740800D03*
X320000Y718200D03*
X323600Y717800D03*
X301310Y726403D03*
X326000Y729000D03*
X315132Y727197D03*
X307278Y726198D03*
X313452Y753856D03*
X330000Y754000D03*
X311200Y765500D03*
X311406Y775198D03*
X302700Y765400D03*
X315406Y765598D03*
Y775200D03*
X307406Y775198D03*
X312017Y827374D03*
X318689D03*
X324616D03*
X331288D03*
X329553Y830301D03*
X316954D03*
X326353D03*
X313754D03*
X306500Y868700D03*
X312000Y868600D03*
X324803Y878276D03*
X331102D03*
X318503D03*
X312500Y878200D03*
X323253Y875176D03*
X310955Y865676D03*
X332651Y875176D03*
X320053D03*
X307755Y865676D03*
X362528Y123931D03*
X358917Y124122D03*
X355069D03*
X352600Y128200D03*
Y132537D03*
X337000Y162000D03*
X354800Y171400D03*
X358300D03*
X354800Y166900D03*
X358300D03*
X354800Y162400D03*
X358300D03*
X362300D03*
Y166900D03*
Y171400D03*
X354800Y181900D03*
X358300D03*
X354800Y176900D03*
X358300D03*
X362300D03*
Y181900D03*
X345820Y256570D03*
X349970Y256720D03*
X344958Y300740D03*
X344955Y305843D03*
X341652Y305034D03*
Y301534D03*
X362500Y341700D03*
X362825Y336000D03*
X359132Y326647D03*
X351515Y327915D03*
X356953Y353653D03*
X359403Y351203D03*
X352003Y358603D03*
X354505Y356102D03*
X360820Y359299D03*
X363270Y356940D03*
X355872Y363965D03*
X358362Y361649D03*
X359500Y448800D03*
X335570Y491460D03*
X342300Y511600D03*
X350000Y537600D03*
X347100Y605300D03*
X357600Y638300D03*
X367000Y704000D03*
X360000D03*
X344200Y696300D03*
X354300Y696000D03*
Y704500D03*
X363500Y704000D03*
X366792Y734171D03*
X364275Y723033D03*
X359500Y727335D03*
X342900Y727200D03*
X364354Y731801D03*
X362091Y729538D03*
X367675Y723000D03*
X349813Y827374D03*
X356485D03*
X362411D03*
X343886D03*
X337214D03*
X367348Y830301D03*
X354750D03*
X342151D03*
X364148D03*
X351550D03*
X338951D03*
X362599Y878276D03*
X356299D03*
X350000D03*
X343700D03*
X337402D03*
X361048Y875176D03*
X348450D03*
X335851D03*
X357848D03*
X345250D03*
X387669Y5500D03*
X401300Y159800D03*
X401200Y150200D03*
X401300Y156715D03*
Y153215D03*
X400400Y189100D03*
X383600Y203200D03*
X376600Y261350D03*
X381700Y265800D03*
X368900Y315700D03*
X370700Y353900D03*
X395100Y449100D03*
X380300Y508700D03*
X401000Y575500D03*
X372000Y579300D03*
X388900Y550400D03*
X386500Y607900D03*
X370500Y705500D03*
X374275Y722919D03*
X370875Y723000D03*
X369083Y827374D03*
X384459D03*
X391131D03*
X397057D03*
X401994Y830301D03*
X389396D03*
X398794D03*
X386196D03*
X378346Y878276D03*
X390944D03*
X397244D03*
X384646D03*
X370500Y878200D03*
X395694Y875176D03*
X383096D03*
X392494D03*
X379896D03*
X407669Y5500D03*
X427669D03*
X406500Y141700D03*
X403600Y142542D03*
X433000Y169700D03*
X406500Y146900D03*
X435161Y166892D03*
X403600Y146042D03*
X422876Y199830D03*
Y204195D03*
X421757Y177999D03*
X411400Y183900D03*
X433400Y176800D03*
X410900Y217100D03*
X404170Y326708D03*
X403900Y315492D03*
X404040Y318900D03*
Y323300D03*
X416100Y470800D03*
X418900Y529300D03*
X410300Y637500D03*
X416328Y827374D03*
X428926D03*
X422254D03*
X403729D03*
X409656D03*
X427191Y830301D03*
X414593D03*
X423991D03*
X411393D03*
X416141Y878276D03*
X431889D03*
X422441D03*
X403543D03*
X409843D03*
X420891Y875176D03*
X408292D03*
X417691D03*
X405092D03*
X447669Y5500D03*
X467669D03*
X461900Y62300D03*
X466000D03*
X457700D03*
X465127Y57727D03*
X452600Y114254D03*
X454871Y122291D03*
X457400Y138900D03*
X454926Y118791D03*
X455800Y110200D03*
X452500Y153300D03*
X438561Y166892D03*
X456500Y169783D03*
Y165418D03*
X455800Y208300D03*
X464086Y287614D03*
X461389Y318510D03*
X464086Y340500D03*
X459200Y369300D03*
X462700D03*
X455450Y376050D03*
X466700Y388800D03*
X469700Y393300D03*
X459450Y384050D03*
X448200Y531400D03*
X443000Y596500D03*
X469000Y784000D03*
X461300Y813100D03*
X457900D03*
X456335Y835051D03*
X444500Y864450D03*
X438189Y878276D03*
X489261Y-14185D03*
X470200Y62300D03*
X478400D03*
X474400D03*
X483250Y59480D03*
X479700Y90100D03*
X491466Y126683D03*
X496782Y134315D03*
X474990Y122660D03*
X494800Y162900D03*
X480910Y164099D03*
X480800Y160700D03*
X498900Y171800D03*
X498000Y194200D03*
X493186Y272414D03*
X501867Y295490D03*
X477037Y333841D03*
X473637Y333876D03*
X500198Y324041D03*
X480532Y321332D03*
X480000Y355800D03*
X476600D03*
X486700Y363800D03*
X470200D03*
X493700Y369300D03*
X490200Y388800D03*
X491860Y382140D03*
X487000Y393300D03*
X480368Y405606D03*
X476531D03*
X472600Y477700D03*
X487400Y492100D03*
X500800Y567200D03*
X487906Y768598D03*
X491906Y768531D03*
X496061Y781678D03*
X482925Y777422D03*
X489522Y780127D03*
X478000Y777500D03*
X483850Y773800D03*
X500778Y781031D03*
X499906Y768531D03*
X497910Y778824D03*
X495906Y768598D03*
X494582Y800500D03*
X483500Y784650D03*
X485300Y808250D03*
X480100Y784575D03*
X497000Y817500D03*
X483000Y788150D03*
X499000Y793000D03*
X485300Y811750D03*
X500415Y817532D03*
X494582Y804000D03*
X496335Y835051D03*
X480406Y827531D03*
X495878Y827431D03*
X477206Y820648D03*
X500700Y828100D03*
X500807Y831499D03*
X491906Y827403D03*
X487906D03*
X530400Y72400D03*
X524000Y43500D03*
X532500Y62900D03*
X536100Y56700D03*
X531400Y102900D03*
X522700D03*
X528700Y91100D03*
X531200Y87900D03*
X535400Y87400D03*
X532900Y92400D03*
X532400Y78200D03*
X509369Y141559D03*
X530800Y123900D03*
X521465Y140964D03*
X513876D03*
X532110Y138400D03*
X525000D03*
X506006Y126183D03*
X507861Y134154D03*
X519300Y138871D03*
X530177Y140708D03*
X516100Y138871D03*
X526977Y140708D03*
X529176Y151713D03*
X532560Y152046D03*
X534000Y167400D03*
X535960Y151999D03*
X507300Y175500D03*
X515348Y163101D03*
X515354Y168998D03*
X505100Y164800D03*
X503975Y172372D03*
X518686Y163800D03*
Y168200D03*
X512600Y186500D03*
X517599Y229658D03*
X531232Y229927D03*
X534481Y243676D03*
X510462Y261315D03*
X525881Y287776D03*
X534481Y286876D03*
X518277Y288680D03*
X532921Y298436D03*
X509143Y284391D03*
X529881Y287376D03*
X525347Y336979D03*
X512100Y319700D03*
X532499Y315591D03*
X533779Y336979D03*
X507809Y336341D03*
X522209Y333841D03*
X522409Y318441D03*
X529126Y342336D03*
X532978Y371023D03*
X534500Y395100D03*
X528850Y394750D03*
X518100Y453200D03*
X520500Y519400D03*
X527700Y587500D03*
X522500Y782031D03*
X535178Y781000D03*
X511800Y768300D03*
X515900D03*
X531500Y774500D03*
X531600Y770200D03*
X515278Y779198D03*
X519748Y768297D03*
X507729Y778198D03*
X504278Y779198D03*
X507906Y768531D03*
X528179Y782555D03*
X524795Y778529D03*
X511484Y778515D03*
X515650Y764500D03*
X503906Y768598D03*
X519906Y764900D03*
X526274Y806000D03*
X511500Y803000D03*
X532000Y792500D03*
X515000D03*
X524700Y817500D03*
X507044Y817569D03*
X516943Y817401D03*
X528906Y817598D03*
X512716Y817550D03*
X533800Y835500D03*
X508579Y827421D03*
X527500Y836200D03*
X512679Y827500D03*
X527941Y864680D03*
X541200Y73400D03*
X541600Y62600D03*
X544500Y57400D03*
X546800Y46300D03*
X566700Y48700D03*
X570900Y56200D03*
X537400Y91000D03*
X540100Y102900D03*
X541700Y92300D03*
X544600Y87300D03*
X538800Y76900D03*
X546800Y76200D03*
X566100Y103100D03*
X543000Y76300D03*
X539031Y136200D03*
X547400Y136170D03*
X560633Y127988D03*
X552800Y140800D03*
X562603Y140881D03*
X544800Y137769D03*
X541600D03*
X549100Y126900D03*
X566531Y143123D03*
X570754Y147365D03*
X546800Y163450D03*
X564483Y167935D03*
X558121Y167249D03*
X543900Y154800D03*
X550300D03*
X548700Y152200D03*
X545500D03*
X547173Y167987D03*
X561567Y205767D03*
X554149Y200229D03*
X541446Y222562D03*
X569500Y240225D03*
X546494Y216010D03*
X539798Y228856D03*
X539934Y232660D03*
X540035Y236294D03*
X541637Y263240D03*
X545974D03*
X541681Y297976D03*
X539481Y286676D03*
X544993Y281352D03*
X539450Y322166D03*
X539507Y330787D03*
X554400Y335900D03*
X539400Y376444D03*
X560531Y358080D03*
X564100Y358100D03*
X556500Y358000D03*
X561781Y346281D03*
X561300Y369500D03*
X552720Y364180D03*
X539400Y380781D03*
X550000Y381000D03*
X559973Y387638D03*
X561912Y390762D03*
X567150Y415750D03*
X560900Y413700D03*
X544000Y761000D03*
X540500Y781000D03*
X547395Y761198D03*
X540500Y761000D03*
X542500Y806000D03*
X550186Y827374D03*
X543514D03*
X568711D03*
X556113D03*
X562785D03*
X561050Y830301D03*
X548451D03*
X570448D03*
X557850D03*
X545251D03*
X538000Y878200D03*
X550000Y878276D03*
X562598D03*
X568898D03*
X556300D03*
X544000Y878200D03*
X567348Y875176D03*
X554750D03*
X542151D03*
X564148D03*
X551550D03*
X538951D03*
X590000Y46200D03*
X579900Y55800D03*
X588000Y57200D03*
X584600Y63200D03*
X575800Y63100D03*
X588000Y72200D03*
X579000Y72300D03*
X573800Y72400D03*
X576800Y91600D03*
X584600Y78200D03*
X575500Y78500D03*
X588000Y87100D03*
X579000Y87200D03*
X584500Y93200D03*
X580700Y90900D03*
X572500Y91200D03*
X576300Y103300D03*
X585100D03*
X580800Y76000D03*
X574100Y87800D03*
X579200Y140400D03*
X583640Y140636D03*
X598240Y137800D03*
X572990Y140501D03*
X588955Y140600D03*
X591377Y125797D03*
X597846Y125623D03*
X577650Y137780D03*
X587850Y137800D03*
X604450Y137780D03*
X574450D03*
X584650Y137800D03*
X601250Y137780D03*
X593000Y152800D03*
X598300Y152850D03*
X597350Y149950D03*
X594150D03*
X596253Y210000D03*
X603000Y190710D03*
X579811Y179500D03*
X582400Y209500D03*
X597813Y220858D03*
X597763Y242608D03*
X602763Y240858D03*
X597763Y231608D03*
Y235108D03*
Y239108D03*
X602763Y236608D03*
Y232108D03*
X587100Y234800D03*
X587438Y230850D03*
X576100Y234500D03*
X592563Y228308D03*
X588963Y227408D03*
X587400Y238200D03*
X597763Y246108D03*
Y250108D03*
X602763Y245108D03*
Y249608D03*
X604170Y337900D03*
X600800Y337400D03*
X597600Y339100D03*
X599100Y348700D03*
X597500Y352050D03*
X589500Y361000D03*
X581700Y360700D03*
X573900Y360600D03*
X603500Y371200D03*
X576800Y369200D03*
X604400Y421200D03*
X579900Y427400D03*
X584500Y462500D03*
X600400Y538000D03*
X586900Y713200D03*
X593908Y827374D03*
X600580D03*
X587981D03*
X581309D03*
X575383D03*
X598845Y830301D03*
X586246D03*
X573648D03*
X595645D03*
X583046D03*
X594095Y878276D03*
X600393D03*
X587795D03*
X575197D03*
X581497D03*
X592545Y875176D03*
X579947D03*
X601944D03*
X589345D03*
X576747D03*
X631100Y72300D03*
X622100Y72400D03*
X628200Y62600D03*
X619200Y62800D03*
X614300Y55800D03*
X620838Y58628D03*
X634100Y46800D03*
X631300Y57100D03*
X616800Y72200D03*
X624700Y61400D03*
X611100Y103300D03*
X619600D03*
X628300D03*
X615800Y91200D03*
X624400Y91100D03*
X628000Y93000D03*
X618300Y88000D03*
X628100Y77700D03*
X619400Y77500D03*
X631200Y87200D03*
X624000Y76000D03*
X621900Y87600D03*
X619700Y92100D03*
X614721Y138287D03*
X623498Y140671D03*
X629393Y140451D03*
X631940Y137800D03*
X607520Y137780D03*
X605924Y126398D03*
X608089Y131519D03*
X627826Y137880D03*
X638150D03*
X624626D03*
X634950D03*
X617000Y144500D03*
X633900Y149600D03*
X636950Y149650D03*
X635482Y207733D03*
X607700Y211800D03*
X608800Y221400D03*
X635863Y216308D03*
X607763Y242608D03*
Y231608D03*
Y235108D03*
Y239108D03*
X619363Y225108D03*
X623363D03*
X635190Y219641D03*
X631063Y242108D03*
X616970Y235017D03*
X629663Y221708D03*
X616718Y238408D03*
X627363Y224358D03*
X637300Y234500D03*
X607763Y246108D03*
Y250108D03*
X628563Y249108D03*
X624101Y330010D03*
X627500Y329900D03*
X635350Y320850D03*
X622629Y344635D03*
X616640Y342230D03*
X620000Y341500D03*
X606322Y351522D03*
X633000Y356600D03*
Y360500D03*
Y353000D03*
X636500Y356500D03*
X629500D03*
Y371000D03*
X626458Y372521D03*
X616706Y349718D03*
X618680Y346780D03*
X621300Y366900D03*
X609500Y360717D03*
X618600Y357100D03*
X623000Y382500D03*
X617000D03*
X609000Y390350D03*
X615500Y420100D03*
X619100Y418000D03*
X627600Y685000D03*
X608000Y700800D03*
X613178Y827374D03*
X606506D03*
X638375D03*
X631703D03*
X619105D03*
X625777D03*
X636640Y830301D03*
X624042D03*
X611443D03*
X633440D03*
X620842D03*
X608243D03*
X606693Y878276D03*
X619292D03*
X612992D03*
X625590D03*
X631890D03*
X630340Y875176D03*
X617742D03*
X605144D03*
X627140D03*
X614542D03*
X653300Y48600D03*
X665400Y72500D03*
X661100Y73000D03*
X662300Y63300D03*
X656700Y57400D03*
X665696Y57027D03*
X671100Y63400D03*
X656400Y102600D03*
X665100Y102700D03*
X660600Y93300D03*
X669400Y93200D03*
X659700Y86400D03*
X662400Y78100D03*
X667500Y76000D03*
X664000Y91100D03*
X671300Y78100D03*
X641159Y137800D03*
X654500Y143000D03*
X647000D03*
X643160Y149600D03*
X640150Y149650D03*
X640400Y218200D03*
X649400Y234500D03*
X671124Y210770D03*
X655500Y213500D03*
X642463Y241608D03*
X638963D03*
X660700Y212000D03*
X640532Y318099D03*
X643932Y318104D03*
X639500Y342500D03*
X652254Y336353D03*
X643000Y343000D03*
X643750Y321500D03*
X640550D03*
X662897Y346873D03*
X663140Y353982D03*
X646884Y355616D03*
X639500Y371000D03*
X643000Y369500D03*
X648792Y358431D03*
X660244Y352200D03*
Y349000D03*
X653000Y380500D03*
X644100Y488700D03*
X639500Y678500D03*
X657000Y714500D03*
X668500Y700000D03*
X648900Y782500D03*
X645800Y780500D03*
Y776900D03*
Y783900D03*
X666348Y827374D03*
X653750D03*
X660422D03*
X653500Y819100D03*
X671285Y830301D03*
X658687D03*
X668085D03*
X655487D03*
X647838Y872000D03*
X660236Y878276D03*
X666536D03*
X654000Y878200D03*
X642200Y877900D03*
X664986Y875176D03*
X652388D03*
X661786D03*
X649188D03*
X674600Y72200D03*
X676800Y46300D03*
X674300Y102400D03*
X678300Y93100D03*
X674800Y86800D03*
X687900Y208100D03*
X697494Y186256D03*
Y181919D03*
X693300Y181200D03*
X685115Y210677D03*
X674500Y212000D03*
X689500Y344000D03*
X704500Y343000D03*
X676700Y378800D03*
X687000Y378700D03*
X680100Y378718D03*
X683600D03*
X678500Y684000D03*
X673020Y827374D03*
X698217D03*
X691545D03*
X678947D03*
X685619D03*
X698100Y821600D03*
X696482Y830301D03*
X683884D03*
X693282D03*
X680684D03*
X703900Y866100D03*
X697700D03*
X704331Y878276D03*
X698031D03*
X691733D03*
X685433D03*
X679134D03*
X672834D03*
X702400Y868800D03*
X690183Y875176D03*
X677585D03*
X699200Y868800D03*
X686983Y875176D03*
X674385D03*
X728395Y-7315D03*
X713461Y-3006D03*
X736308Y-7483D03*
X711919Y6754D03*
X729132Y3575D03*
X724018Y5719D03*
X729555Y33100D03*
X709120Y35980D03*
X719555Y33100D03*
X735186Y20714D03*
X729000Y24800D03*
X725314Y24751D03*
X721890Y24887D03*
X719008Y21999D03*
X707051Y12174D03*
X738384Y8232D03*
X722955Y33095D03*
X726155D03*
X727265Y52588D03*
X726646Y42651D03*
X721690Y53340D03*
X723200Y42300D03*
X726609Y49251D03*
Y46051D03*
X732900Y44900D03*
X730021Y42235D03*
X723501Y82680D03*
X723481Y76780D03*
X723610Y106430D03*
X723569Y100969D03*
X723659Y97292D03*
X723429Y91683D03*
X735157Y97005D03*
X735326Y102660D03*
X732500Y98421D03*
X720800Y102150D03*
Y93150D03*
Y78150D03*
X732500Y101621D03*
X720800Y105350D03*
Y96350D03*
Y81350D03*
X723438Y112700D03*
X723638Y118353D03*
X720800Y114150D03*
Y117350D03*
X713000Y310000D03*
X724400Y626500D03*
X712495Y816195D03*
X735640Y827374D03*
X723041D03*
X729713D03*
X727978Y830301D03*
X737377D03*
X724778D03*
X714900Y818600D03*
X729527Y878276D03*
X735827D03*
X723000Y878200D03*
X734277Y875176D03*
X731077D03*
X746329Y-7789D03*
X771715Y6840D03*
X752763Y38638D03*
X771600Y24200D03*
X741600Y41000D03*
X747000Y44300D03*
X762250Y44650D03*
X742290Y68550D03*
X750130Y63340D03*
X748300Y53800D03*
X772000Y64200D03*
X753500Y96600D03*
X755700Y79100D03*
X749800Y91400D03*
X753700Y102900D03*
X759600Y79200D03*
X762400Y127600D03*
X753500Y110900D03*
X769400Y111900D03*
X743490Y111940D03*
X765000Y112800D03*
X768777Y171450D03*
X761242Y169242D03*
X765579D03*
X771400Y185919D03*
X766244Y185897D03*
X748237Y194042D03*
X751737D03*
X766950Y189252D03*
X763562Y189539D03*
X770385Y189165D03*
X749337Y212192D03*
X746037Y213992D03*
X746237Y210392D03*
X743500Y362000D03*
X753000Y359000D03*
X743000Y598000D03*
X773435Y827374D03*
X754910D03*
X748238D03*
X742312D03*
X760837D03*
X767509D03*
X765774Y830301D03*
X753175D03*
X740577D03*
X762574D03*
X749975D03*
X754724Y878276D03*
X761024D03*
X767323D03*
X742126D03*
X748426D03*
X772073Y875176D03*
X759474D03*
X746876D03*
X768873D03*
X756274D03*
X743676D03*
X790150Y-1400D03*
X788408Y-4321D03*
X798061Y-6439D03*
X788550Y29350D03*
X806152Y51692D03*
X791300Y74200D03*
X775381Y66115D03*
X778800Y66388D03*
X782551Y67144D03*
X786333Y66963D03*
X781500Y85100D03*
X797800Y104500D03*
X776538Y107162D03*
X773900Y138300D03*
X791200Y125300D03*
X796051Y175147D03*
X806665Y174050D03*
X803265D03*
X792760Y176043D03*
X799000Y196000D03*
X802200D03*
X796089Y181182D03*
X775397Y179165D03*
Y184215D03*
X792390Y199166D03*
X786463Y199019D03*
X803169Y198850D03*
X797890Y198918D03*
X792000Y195778D03*
X787600Y195804D03*
X773984Y189118D03*
X792760Y180443D03*
X778807Y183890D03*
Y179490D03*
X780800Y545900D03*
X786033Y827374D03*
X780107D03*
X792705D03*
X798632D03*
X805304D03*
X803569Y830301D03*
X790970D03*
X778372D03*
X800369D03*
X787770D03*
X775172D03*
X779921Y878276D03*
X786221D03*
X792519D03*
X798819D03*
X805118D03*
X773623D03*
X797270Y875176D03*
X784671D03*
X806668D03*
X794070D03*
X781471D03*
X807514Y2199D03*
X813900Y12900D03*
X830773Y9000D03*
X834227D03*
X831592Y34411D03*
X838252Y20800D03*
X834500D03*
X830500D03*
X828283Y24734D03*
X824462Y25770D03*
X821877Y21090D03*
X823996Y44276D03*
X832401Y46472D03*
X831125Y67775D03*
X820004Y44234D03*
X828700Y48800D03*
X808114Y67634D03*
X816043Y94981D03*
Y99318D03*
X823551Y80551D03*
X819000Y97100D03*
X809000Y76000D03*
X810000Y109400D03*
X833900Y467000D03*
X812500Y499400D03*
X840500Y735500D03*
X837000D03*
X839990Y789230D03*
X836427Y827374D03*
X817902D03*
X811230D03*
X816167Y830301D03*
X838164D03*
X812967D03*
X836615Y878276D03*
X830315D03*
X811418D03*
X820000Y878200D03*
X835065Y875176D03*
X809868D03*
X831865D03*
X861000Y350D03*
X857453Y303D03*
X867600Y2500D03*
X863300Y23575D03*
X851100Y9100D03*
X855489Y9811D03*
X859300Y9900D03*
X874300Y18875D03*
X858500Y40000D03*
Y32000D03*
X869447Y31024D03*
X843500Y9150D03*
X849051Y20908D03*
X845052Y20800D03*
X841652D03*
X858500Y28000D03*
X858100Y21400D03*
X858500Y36000D03*
X847000Y9100D03*
X870600Y18915D03*
X854252Y20800D03*
X851870Y52160D03*
X859200Y47100D03*
X847337Y46563D03*
X851300Y45748D03*
X848623Y70757D03*
X852019Y70589D03*
X855421Y70551D03*
X858821Y70614D03*
X859000Y43500D03*
X871550Y56450D03*
X858800Y52200D03*
X868800Y49200D03*
X844900Y85100D03*
X868800Y85300D03*
X871696Y87082D03*
X868200Y116000D03*
X846702Y117371D03*
X854400Y117500D03*
X861300Y117800D03*
X851500Y705500D03*
X864800Y707700D03*
X868200D03*
X852500Y718000D03*
X847500Y717500D03*
X857406Y745598D03*
X861406Y745531D03*
X852895Y748648D03*
X869406Y745531D03*
X848000Y735500D03*
X865406Y745598D03*
X873367Y745335D03*
X844000Y735500D03*
X855500Y775500D03*
X844150Y762150D03*
X858695Y759900D03*
X871000Y776500D03*
X854049Y757573D03*
X857406Y755198D03*
X861406D03*
X858126Y763600D03*
X841500Y771000D03*
X874000Y772000D03*
X869562Y758457D03*
X844500Y758000D03*
X867410Y755824D03*
X849906Y804531D03*
X865378Y804431D03*
X851890Y789270D03*
X870900Y812104D03*
X866878Y794531D03*
X853500Y798000D03*
X846706Y797648D03*
X870278Y794531D03*
X874570Y811820D03*
X861406Y804403D03*
X857406D03*
X855697Y827374D03*
X849025D03*
X843099D03*
X853962Y830301D03*
X841364D03*
X850762D03*
X861823Y853696D03*
X849213Y878276D03*
X842913D03*
X856000Y878200D03*
X847663Y875176D03*
X844463D03*
X883800Y-500D03*
X881700Y2300D03*
X899769Y4355D03*
X904262Y14894D03*
X887800Y40100D03*
X880883Y30583D03*
X892745Y9681D03*
X896500Y9500D03*
X877500Y23600D03*
X900250Y38150D03*
X888474Y9173D03*
X900200Y9600D03*
X883800Y41400D03*
X907750Y51750D03*
X894110Y49250D03*
X878800Y49600D03*
X875050Y56250D03*
X895080Y52828D03*
X900501Y48705D03*
X883700Y50700D03*
X905488Y54479D03*
X890000Y97800D03*
X897000Y96700D03*
X878394Y85780D03*
X875001Y86003D03*
X901899Y85942D03*
X892900Y85300D03*
X885042Y85292D03*
X888600Y85700D03*
X897600Y85500D03*
X908500Y270500D03*
Y275000D03*
Y267000D03*
X907500Y325000D03*
X902500Y370000D03*
X897000Y370500D03*
X907500Y368000D03*
X900999Y748550D03*
X885400Y743600D03*
X895800Y738400D03*
X893400Y745100D03*
X884700Y721100D03*
X896500Y734000D03*
X877000Y745000D03*
X892100Y721100D03*
X881200Y721300D03*
X888400Y721400D03*
X900824Y781531D03*
X895278Y758885D03*
X874887Y759253D03*
X884671Y775500D03*
X889900Y769600D03*
X884778Y756198D03*
X876036Y755481D03*
X894465Y755501D03*
X891056Y755641D03*
X882227Y758835D03*
X885167Y816593D03*
X894200Y794500D03*
X877930Y796880D03*
X876470Y808710D03*
X906396Y810300D03*
X886288Y794372D03*
X898700Y794200D03*
Y816000D03*
X882290Y796770D03*
X881720Y807390D03*
X906450Y806900D03*
X906092Y813687D03*
X884412Y835051D03*
X894406Y818000D03*
X888100Y823338D03*
X890200Y819200D03*
X912000Y41000D03*
X927250Y31450D03*
X911800Y37000D03*
X938000Y30300D03*
X919400Y33300D03*
X915486Y41030D03*
X918952Y40680D03*
X912000Y45000D03*
X939064Y58104D03*
X934881Y57322D03*
X909797Y55037D03*
X910000Y85300D03*
X937642Y85562D03*
X926093Y85239D03*
X929213Y86593D03*
X934438Y86700D03*
X919050Y85500D03*
X913979Y86580D03*
X935000Y97400D03*
X927100Y96900D03*
X929800Y105900D03*
X909000Y279000D03*
X909500Y283000D03*
Y338000D03*
X909000Y353600D03*
X908700Y347300D03*
X938898Y640169D03*
X916319Y678588D03*
Y658588D03*
Y698588D03*
Y738588D03*
Y718588D03*
Y778588D03*
Y758588D03*
Y798588D03*
Y818588D03*
X969100Y14600D03*
X942500Y30100D03*
X974100Y19600D03*
X970064Y18764D03*
X963700Y21700D03*
X959877Y26978D03*
X967180Y66705D03*
X952500Y75100D03*
X949102Y74964D03*
X947900Y67900D03*
X959300Y68600D03*
Y72000D03*
X964105Y62308D03*
X959855Y61107D03*
X956687Y85482D03*
X942800Y85700D03*
X948200Y85900D03*
X953301Y85793D03*
X956500Y108000D03*
X949500Y103000D03*
Y97500D03*
X949893Y106378D03*
X949828Y109778D03*
X957800Y570300D03*
X960500Y607000D03*
X953500D03*
X956900D03*
X958898Y640169D03*
X976500Y4500D03*
X1008353Y-1940D03*
X985579Y26494D03*
X985403Y22993D03*
X980100Y14500D03*
X1000985Y29307D03*
X1007921Y39585D03*
X985315Y14425D03*
X997385Y29307D03*
X994650Y39880D03*
X992396Y45073D03*
X990628Y49698D03*
X997007Y49560D03*
X1008508Y47704D03*
X982500Y271500D03*
Y275500D03*
X982000Y267500D03*
X983500Y279500D03*
Y283500D03*
X1006100Y528700D03*
X977500Y550000D03*
X978898Y640169D03*
X994248Y665818D03*
Y685818D03*
Y705818D03*
Y745818D03*
Y725818D03*
Y765818D03*
Y805818D03*
Y785818D03*
X1025700Y7600D03*
X1022711Y-4975D03*
X1012177Y-2940D03*
X1019859Y-7642D03*
X1033017Y14743D03*
X1024330Y34379D03*
X1040218Y32140D03*
X1010229Y19022D03*
X1022300Y13900D03*
X1033554Y30216D03*
X1040121Y26870D03*
X1039822Y35743D03*
X1017908Y41556D03*
X1018900Y14198D03*
X1010975Y29017D03*
X1029553Y13981D03*
X1030139Y30209D03*
X1024432Y43718D03*
X1035783Y51473D03*
X1017863Y45056D03*
X1011300Y53000D03*
X1024318Y51554D03*
X1014700Y53700D03*
X1040241Y61043D03*
X1033517Y48934D03*
X1036854Y47110D03*
X1019900Y108500D03*
X1015948D03*
X1034500D03*
X1027483Y108431D03*
X1024000Y108500D03*
X1037900D03*
X1041300D03*
X1030883Y108438D03*
X1028500Y257500D03*
X1012600Y476700D03*
X1022600Y542100D03*
X1017800Y572700D03*
X1043300Y631300D03*
X1041500Y682000D03*
X1041900Y658100D03*
X1039577Y827374D03*
X1041314Y830301D03*
X1024004Y855893D03*
X1033464Y878276D03*
X1039764D03*
X1038214Y875176D03*
X1035014D03*
X1062044Y-4173D03*
X1065620Y-4335D03*
X1072800Y-800D03*
X1069261Y-14185D03*
X1049261D03*
X1045850Y6228D03*
X1069200Y-4200D03*
X1060800Y10100D03*
X1061253Y17487D03*
X1062470Y31823D03*
X1062433Y37099D03*
X1056049Y18396D03*
X1061153Y27488D03*
X1046200Y24500D03*
X1054835Y40386D03*
X1072140Y16447D03*
X1047429Y15229D03*
X1044050Y28815D03*
X1062088Y40597D03*
X1072804Y19894D03*
X1064900Y10400D03*
X1065700Y32888D03*
Y36088D03*
X1061200Y20888D03*
Y24088D03*
X1056200Y10100D03*
X1065657Y28946D03*
X1047500Y41500D03*
X1051000D03*
X1076970Y30411D03*
X1052600Y14400D03*
X1054210Y53370D03*
X1054090Y58470D03*
X1068315Y56120D03*
X1068390Y61611D03*
X1074103Y44988D03*
X1049772Y57259D03*
X1049470Y53749D03*
X1050875Y61090D03*
X1057000Y54500D03*
X1071135Y60375D03*
X1057000Y57700D03*
X1071135Y57175D03*
X1057000Y107700D03*
X1057259Y77276D03*
X1048100Y108500D03*
X1044700D03*
X1061000Y111000D03*
X1053000Y109500D03*
X1047000Y644000D03*
X1045000Y617500D03*
X1067000Y711000D03*
X1062500Y738000D03*
X1058500Y758000D03*
X1058847Y827374D03*
X1052175D03*
X1046249D03*
X1064774D03*
X1071446D03*
X1069711Y830301D03*
X1057112D03*
X1044514D03*
X1066511D03*
X1053912D03*
X1046063Y878276D03*
X1071260D03*
X1064961D03*
X1058661D03*
X1052363D03*
X1076010Y875176D03*
X1050813D03*
X1072810D03*
X1047613D03*
X1084000Y500D03*
X1089261Y-14185D03*
X1083315Y36654D03*
X1082808Y30601D03*
X1092094Y30362D03*
X1080672Y9500D03*
X1084800Y9400D03*
X1083379Y40889D03*
X1083500Y25500D03*
X1082974Y14467D03*
X1105441Y54768D03*
X1100992Y52374D03*
X1078694Y43478D03*
X1103424Y67690D03*
X1077432Y64225D03*
X1103300Y73900D03*
X1103349Y70700D03*
X1088005Y46541D03*
X1088287Y55917D03*
X1096496Y51226D03*
X1110664Y78483D03*
X1103253Y76910D03*
X1079500Y631000D03*
X1080000Y650500D03*
X1081000Y670000D03*
X1084044Y827374D03*
X1077372D03*
X1102569D03*
X1109241D03*
X1089970D03*
X1096642D03*
X1107506Y830301D03*
X1094907D03*
X1082309D03*
X1104306D03*
X1091707D03*
X1079109D03*
X1090158Y878276D03*
X1083858D03*
X1077560D03*
X1096456D03*
X1102756D03*
X1109055D03*
X1101207Y875176D03*
X1088608D03*
X1110605D03*
X1098007D03*
X1085408D03*
X1127300Y46300D03*
X1122800Y55100D03*
X1132100Y56300D03*
X1131900Y70700D03*
X1140900Y71100D03*
X1141900Y63300D03*
X1142418Y78638D03*
X1131800Y85600D03*
X1141200Y86800D03*
X1126400Y92200D03*
X1143500Y93300D03*
X1123000Y99200D03*
X1131880Y100377D03*
X1134800Y93300D03*
X1116933Y85243D03*
X1112700Y80700D03*
X1114842Y83078D03*
X1122001Y126574D03*
Y136874D03*
X1135150Y137851D03*
X1122001Y133324D03*
X1141900Y137851D03*
X1122001Y130124D03*
X1138700Y137851D03*
X1126500Y222500D03*
X1135750Y228750D03*
X1143000Y242000D03*
X1140364Y827374D03*
X1121839D03*
X1115167D03*
X1127766D03*
X1134438D03*
X1132703Y830301D03*
X1120104D03*
X1142101D03*
X1129503D03*
X1116904D03*
X1140552Y878276D03*
X1115355D03*
X1127953D03*
X1134252D03*
X1121653D03*
X1139002Y875176D03*
X1126403D03*
X1113805D03*
X1135802D03*
X1123203D03*
X1175300Y71100D03*
X1175100Y55700D03*
X1166500Y56200D03*
X1171700Y45900D03*
X1149100Y46300D03*
X1150700Y63300D03*
X1148900Y75900D03*
X1168400Y103000D03*
X1177000Y102800D03*
X1176200Y92900D03*
X1178100Y78000D03*
X1175200Y85900D03*
X1151492Y78668D03*
X1164857Y138505D03*
X1154557D03*
X1145450Y137851D03*
X1175851Y142410D03*
X1161307Y138505D03*
X1158107D03*
X1170400Y144100D03*
X1150250Y228750D03*
X1147000Y242000D03*
X1151000D03*
X1161700Y818500D03*
X1159634Y827374D03*
X1152962D03*
X1147036D03*
X1175010D03*
X1174900Y818300D03*
X1157899Y830301D03*
X1145301D03*
X1176747D03*
X1154699D03*
X1159448Y878276D03*
X1153150D03*
X1173623Y878200D03*
X1146850Y878276D03*
X1165748D03*
X1164199Y875176D03*
X1151600D03*
X1160999D03*
X1148400D03*
X1185200Y72600D03*
X1210511Y52300D03*
X1193555Y61875D03*
X1183884Y61598D03*
X1188200Y61600D03*
X1192300Y46100D03*
X1184100Y56100D03*
X1193900Y78000D03*
X1211500Y102900D03*
X1194000Y93200D03*
X1185800Y102900D03*
X1185100Y93000D03*
X1187100Y77900D03*
X1184800Y87200D03*
X1202410Y142850D03*
X1193845Y137855D03*
X1184629Y137740D03*
X1185070Y142384D03*
X1182061Y142478D03*
X1190835Y137899D03*
X1199400Y142851D03*
X1178861Y142478D03*
X1187635Y137899D03*
X1196200Y142851D03*
X1210391Y156730D03*
X1200391Y156779D03*
X1193192Y142970D03*
X1206991Y156730D03*
X1203791D03*
X1205500Y334400D03*
X1201000Y417900D03*
X1196600Y416200D03*
X1194280Y827374D03*
X1187608D03*
X1181682D03*
X1192545Y830301D03*
X1179947D03*
X1189345D03*
X1200735Y864273D03*
X1194063D03*
X1200394Y878276D03*
X1194094D03*
X1187796D03*
X1181496D03*
X1199000Y867200D03*
X1186246Y875176D03*
X1195800Y867300D03*
X1183046Y875176D03*
X1231400Y58300D03*
X1215400Y57600D03*
X1216300Y72900D03*
X1235800Y46400D03*
X1228000Y57000D03*
X1218600Y56000D03*
X1214700Y46000D03*
X1221200Y63400D03*
X1230300Y63200D03*
X1228900Y72900D03*
X1230000Y78800D03*
X1221300Y78400D03*
X1219200Y87000D03*
X1229100Y87900D03*
X1232500Y90900D03*
X1229900Y103100D03*
X1228300Y93100D03*
X1219500Y93300D03*
X1220100Y102700D03*
X1219138Y137928D03*
X1227999Y142465D03*
X1236692Y137720D03*
X1237219Y142420D03*
X1228359Y137960D03*
X1214795Y142443D03*
X1234209Y142463D03*
X1242900Y137851D03*
X1225348Y137960D03*
X1231009Y142463D03*
X1239700Y137851D03*
X1222148Y137960D03*
X1242621Y153690D03*
X1226000Y261300D03*
X1242000Y343000D03*
X1235400Y364400D03*
X1213400Y355400D03*
X1214100Y469800D03*
X1237800Y524500D03*
X1232300Y568900D03*
X1238375Y827374D03*
X1231703D03*
X1219105D03*
X1225777D03*
X1244302D03*
X1236640Y830301D03*
X1224042D03*
X1233440D03*
X1220842D03*
X1217717Y878076D03*
X1225590Y878276D03*
X1231890D03*
X1244489D03*
X1238189D03*
X1242939Y875176D03*
X1230340D03*
X1239739D03*
X1227140D03*
X1261900Y71039D03*
X1265500Y61900D03*
X1272200Y72900D03*
X1275200Y61200D03*
X1269900Y61100D03*
X1279100Y46300D03*
X1272200Y57900D03*
X1258400Y45900D03*
X1254500Y51100D03*
X1271300Y77100D03*
X1273200Y103200D03*
X1256000Y103300D03*
X1263200Y102700D03*
X1270300Y91100D03*
X1262800Y93100D03*
X1254200Y96300D03*
X1275500Y91000D03*
X1272700Y88000D03*
X1265200Y77400D03*
X1261900Y86000D03*
X1275800Y75900D03*
X1252768Y141181D03*
X1278160Y140547D03*
X1257899Y142881D03*
X1245910Y137810D03*
X1273068Y140514D03*
X1277265Y137673D03*
X1274065D03*
X1262880Y142909D03*
X1273499Y151498D03*
X1273520Y148070D03*
X1261944Y145770D03*
X1258744D03*
X1251801Y144871D03*
X1275500Y264500D03*
X1258500Y335500D03*
X1266500D03*
X1255000Y317300D03*
X1270500Y335500D03*
X1272500Y350000D03*
X1275060Y345690D03*
X1277620Y349500D03*
X1264820Y349320D03*
X1273500Y397000D03*
X1257500D03*
X1254000D03*
X1249250Y390250D03*
X1269500Y397000D03*
X1273500Y400500D03*
X1258000Y421500D03*
X1259200Y471800D03*
X1259000Y680000D03*
X1265000Y672000D03*
X1253500D03*
X1278000Y689000D03*
X1263572Y827374D03*
X1269498D03*
X1276170D03*
X1256900D03*
X1250974D03*
X1274435Y830301D03*
X1261837D03*
X1249239D03*
X1271235D03*
X1258637D03*
X1246039D03*
X1263386Y878276D03*
X1275984D03*
X1257087D03*
X1269686D03*
X1250787D03*
X1268136Y875176D03*
X1255537D03*
X1277534D03*
X1264936D03*
X1252337D03*
X1303983Y22083D03*
X1304000Y44000D03*
Y67500D03*
Y90500D03*
X1291660Y140257D03*
X1297360Y140172D03*
X1301749Y125479D03*
X1286543Y141581D03*
X1296017Y137478D03*
X1283343Y141581D03*
X1292817Y137478D03*
X1282189Y144361D03*
X1287637Y144386D03*
X1297668Y155524D03*
X1290870Y186285D03*
X1311181Y186548D03*
X1290000Y271000D03*
X1308500Y262500D03*
X1311200Y256500D03*
X1293500Y271000D03*
X1312200Y275200D03*
X1303700Y289500D03*
X1288900Y304000D03*
X1283300Y302900D03*
X1309900Y292400D03*
X1310500Y285500D03*
X1297500Y351800D03*
X1281900Y346580D03*
X1282740Y350010D03*
X1311500Y391000D03*
X1310068Y394084D03*
X1297625Y382375D03*
X1296500Y386500D03*
X1290125Y382875D03*
X1289500Y386500D03*
X1282740Y383000D03*
X1282000Y386500D03*
X1291600Y495200D03*
X1296400Y542400D03*
X1294700Y593400D03*
X1301000Y618500D03*
X1300000Y637000D03*
X1302128Y674067D03*
X1306128Y674000D03*
X1297617Y677117D03*
X1286800Y671100D03*
X1297500Y664000D03*
X1310207D03*
X1297400Y651300D03*
X1290550D03*
X1285000Y694000D03*
X1280500Y706000D03*
X1310376Y687205D03*
X1301728Y711200D03*
X1302000Y695500D03*
X1302128Y685500D03*
X1307000Y686500D03*
X1304500Y698000D03*
X1301728Y714600D03*
X1312132Y684293D03*
X1310100Y732900D03*
X1294628Y733000D03*
X1310500Y723000D03*
X1291428Y726117D03*
X1306128Y732872D03*
X1302128D03*
X1304800Y811900D03*
X1288768Y827374D03*
X1282096D03*
X1307294D03*
X1312231Y830301D03*
X1287033D03*
X1309031D03*
X1283833D03*
X1301800Y878100D03*
X1294268Y872169D03*
X1288582Y878276D03*
X1282284D03*
X1307481D03*
X1305931Y875176D03*
X1293333D03*
X1280734D03*
X1302731D03*
X1290133D03*
X1324845Y130527D03*
X1339471Y139268D03*
X1325429Y148270D03*
X1316590Y147210D03*
X1317400Y143620D03*
X1340130Y145980D03*
X1331243Y182198D03*
X1337000Y263250D03*
X1332000Y261500D03*
Y265000D03*
Y268500D03*
Y272500D03*
Y257500D03*
Y254000D03*
X1342000D03*
Y257500D03*
Y261500D03*
Y265000D03*
Y268500D03*
Y272500D03*
X1337000Y267500D03*
Y272000D03*
Y259000D03*
Y254500D03*
X1322000Y276500D03*
X1322500Y266800D03*
X1333500Y290500D03*
X1317026Y304858D03*
X1322250Y282250D03*
X1314000Y286500D03*
X1345850Y676750D03*
X1313607Y664000D03*
X1327200Y661800D03*
X1331000Y662000D03*
X1326128Y674000D03*
X1340000D03*
X1317007Y664000D03*
X1334128Y674000D03*
X1333500Y709500D03*
X1323076Y686999D03*
X1338200Y689800D03*
X1315546Y709500D03*
X1341400Y686900D03*
X1337500Y698000D03*
X1322439Y697767D03*
X1315000Y686500D03*
X1329500Y684667D03*
X1321928Y683798D03*
X1318500Y684667D03*
X1339934Y683832D03*
X1336795Y685141D03*
X1326758Y686678D03*
X1314628Y733000D03*
X1315000Y723000D03*
X1326661Y740700D03*
X1333500Y723000D03*
X1334128Y732667D03*
X1325600Y722987D03*
X1342000Y732500D03*
X1337500Y723000D03*
X1340500Y742500D03*
X1338128Y732872D03*
X1330128Y732667D03*
X1345088Y827374D03*
X1332490D03*
X1339162D03*
X1326564D03*
X1319892D03*
X1313966D03*
X1337427Y830301D03*
X1324829D03*
X1346825D03*
X1334227D03*
X1321629D03*
X1320079Y878276D03*
X1345276D03*
X1332678D03*
X1338976D03*
X1326378D03*
X1313779D03*
X1343726Y875176D03*
X1331128D03*
X1318529D03*
X1340526D03*
X1327928D03*
X1315329D03*
X1368028Y175745D03*
X1359128Y167226D03*
X1355321Y172119D03*
X1354971Y167446D03*
X1365804Y185197D03*
X1368300Y267800D03*
X1358662Y275485D03*
X1355066Y275228D03*
X1348500Y276500D03*
X1361500Y273500D03*
X1352000Y276700D03*
X1352500Y267000D03*
X1369300Y259300D03*
X1355000Y286300D03*
X1364000Y280500D03*
X1369700Y424600D03*
X1366000Y472900D03*
X1363900Y537600D03*
X1361800Y596800D03*
X1358700Y655700D03*
X1351500Y675000D03*
X1348500Y713000D03*
X1377000Y725000D03*
X1378000Y806900D03*
X1369925Y835051D03*
X1351760Y827374D03*
X1350025Y830301D03*
X1357886Y864246D03*
X1352200Y878400D03*
X1394500Y139626D03*
Y119626D03*
Y159626D03*
X1381696Y173459D03*
X1387196Y174160D03*
X1394500Y199626D03*
Y179626D03*
X1381568Y180579D03*
X1382138Y184129D03*
X1385467Y180543D03*
X1394500Y239626D03*
Y219626D03*
Y259626D03*
Y299626D03*
Y279626D03*
Y339626D03*
Y319626D03*
Y359626D03*
Y399626D03*
Y379626D03*
Y439626D03*
Y419626D03*
Y479626D03*
Y459626D03*
Y499626D03*
Y539626D03*
Y519626D03*
Y579626D03*
Y559626D03*
Y599626D03*
Y639626D03*
Y619626D03*
Y679626D03*
Y659626D03*
Y699626D03*
Y739626D03*
Y719626D03*
Y759626D03*
Y779626D03*
Y799626D03*
Y819626D03*
X1389925Y835051D03*
G54D21*
X51370Y301816D03*
X51377Y298371D03*
X51200Y307100D03*
X61782Y295207D03*
X51378Y294934D03*
X41200Y422000D03*
Y426000D03*
X137200Y510500D03*
X136972Y505467D03*
X138216Y517120D03*
X138700Y522000D03*
X269200Y759000D03*
X551680Y137538D03*
X551700Y134094D03*
X622700Y354600D03*
X830000Y176200D03*
Y179700D03*
X871500Y52700D03*
X1036217Y14710D03*
X1324200Y250000D03*
G54D30*
X96700Y476400D03*
Y472400D03*
X84042Y463549D03*
X80900Y478600D03*
X96700Y484600D03*
Y480400D03*
X74200Y498500D03*
X73808Y506552D03*
X84200Y546500D03*
Y530500D03*
Y542500D03*
Y522500D03*
Y550500D03*
X84022Y562789D03*
X80100Y729300D03*
Y733300D03*
X117800Y288100D03*
X111800Y731900D03*
Y727900D03*
X142546Y430391D03*
X192900Y403300D03*
X193100Y419800D03*
X214202Y479619D03*
Y475619D03*
X210226Y448165D03*
X226238Y466300D03*
Y462300D03*
X214423Y487704D03*
Y483704D03*
X213450Y495744D03*
Y491744D03*
X213200Y525500D03*
Y521500D03*
Y534500D03*
Y530500D03*
X226200Y550500D03*
Y558500D03*
Y554500D03*
X243200Y478000D03*
X265238Y477600D03*
X253200Y494100D03*
X243200Y490000D03*
Y486000D03*
Y482000D03*
X265238Y481600D03*
X263700Y588500D03*
Y593000D03*
X297700Y578500D03*
Y583000D03*
Y588500D03*
X510400Y788700D03*
X715563Y37236D03*
X718770Y29700D03*
X718790Y25490D03*
X718530Y53200D03*
Y49100D03*
X866260Y788880D03*
X881910Y792910D03*
X956200Y67900D03*
Y72000D03*
X1020546Y57597D03*
X1046900Y36615D03*
G54D12*
X31977Y126614D03*
Y116614D03*
X91189Y126614D03*
Y116614D03*
Y136614D03*
G54D40*
X120351Y626636D03*
X126851D03*
X143217Y498160D03*
X156862Y498211D03*
X152916Y497936D03*
X146960Y498030D03*
X165851Y624136D03*
X137551Y622136D03*
X149851Y624136D03*
X155851D03*
X160851D03*
X217000Y534700D03*
X221000Y525700D03*
X500332Y130164D03*
X493245Y130025D03*
X489680Y130005D03*
X503827Y130104D03*
X563002Y133795D03*
X559591D03*
X597044Y130268D03*
X593636D03*
X600522Y130253D03*
X603924D03*
X635500Y346300D03*
X630500D03*
X627000D03*
X639000D03*
X848660Y785690D03*
X1175156Y134519D03*
X1171622Y136228D03*
X1168207Y136226D03*
X1178558Y134518D03*
X1240709Y146753D03*
X1237308D03*
X1269834Y143834D03*
X1266432D03*
X1289500Y274200D03*
G54D22*
X50800Y334700D03*
Y342300D03*
X85400Y268400D03*
Y260800D03*
X87561Y317727D03*
Y325327D03*
X228500Y142700D03*
Y150300D03*
X582363Y237408D03*
Y229808D03*
X669163Y243108D03*
Y250708D03*
X693163Y243108D03*
X677163D03*
X685163D03*
X704700Y278200D03*
X693163Y250708D03*
X677163D03*
X685163D03*
X704700Y285800D03*
X708600Y238700D03*
X716600D03*
X724600D03*
X732600D03*
X708600Y246300D03*
X716600D03*
X724600D03*
X732600D03*
X719900Y278200D03*
X712300D03*
X735100D03*
X727500D03*
X719900Y285800D03*
X712300D03*
X735100D03*
X727500D03*
X1242000Y221800D03*
Y214200D03*
X1234000Y221800D03*
Y214200D03*
X1236500Y266200D03*
Y273800D03*
X1228500Y266200D03*
Y273800D03*
X1244500Y266200D03*
Y273800D03*
X1250000Y221800D03*
Y214200D03*
X1258500Y221800D03*
Y214200D03*
X1252500Y266200D03*
Y273800D03*
X1260500Y266200D03*
Y273800D03*
X1363500Y260200D03*
Y267800D03*
G54D31*
X72900Y733100D03*
X148500Y525300D03*
X158500Y526300D03*
X221000Y521800D03*
X294500Y149300D03*
X290178Y736231D03*
X273500Y736200D03*
X322178Y736231D03*
X306178D03*
X503178Y788231D03*
X487000Y788200D03*
X488500Y811800D03*
X535178Y788231D03*
X519069Y788767D03*
X556531Y364880D03*
X560531D03*
X635500Y366900D03*
X645663Y238308D03*
X639000Y366900D03*
X847500Y765700D03*
X862678Y765731D03*
X892678Y765231D03*
X1204335Y138491D03*
X1207745Y138490D03*
X1266432Y154937D03*
X1269834D03*
X1307400Y693700D03*
X1306000Y716800D03*
X1324900Y693700D03*
X1341400D03*
G54D13*
X26977Y151614D03*
X96189D03*
G54D50*
X276700Y143300D03*
X626763Y238108D03*
X647000Y788200D03*
X946600Y44100D03*
X1313100Y266500D03*
X1363500Y254500D03*
G54D14*
X31300Y268800D03*
X38900D03*
X39700Y278500D03*
X32100D03*
X39800Y308300D03*
X32200D03*
X57100Y315100D03*
X64700D03*
X98020Y307120D03*
X89776Y291298D03*
X82176D03*
X105620Y307120D03*
X248700Y177000D03*
X256300D03*
X267700Y166000D03*
X248700Y185000D03*
X256300D03*
X275300Y166000D03*
X570063Y253608D03*
X592763Y256608D03*
X600363D03*
X577663Y253608D03*
X628863Y254608D03*
X621263D03*
X628600Y362100D03*
X621000D03*
X930300Y267000D03*
X922700D03*
X930300Y275000D03*
X922700D03*
X930300Y283000D03*
X922700D03*
X965200Y267500D03*
X972800D03*
X965200Y275500D03*
X972800D03*
X965200Y283500D03*
X972800D03*
X1311200Y250500D03*
X1346300Y240000D03*
X1338700D03*
X1346300Y248000D03*
X1338700D03*
X1318800Y250500D03*
G54D41*
X115355Y887970D03*
X118504D03*
X121654D03*
X124803D03*
X127953D03*
X131103D03*
X134252D03*
X137402D03*
X140551D03*
X143701D03*
X146851D03*
X150000D03*
X153150D03*
X156300D03*
X159449D03*
X162599D03*
X165748D03*
X168898D03*
X172048D03*
X175197D03*
X178347D03*
X181496D03*
X184646D03*
X187796D03*
X190945D03*
X194095D03*
X197244D03*
X200394D03*
X203544D03*
X206693D03*
X209843D03*
X212992D03*
X216142D03*
X219292D03*
X222441D03*
X225591D03*
X228740D03*
X231890D03*
X235040D03*
X238189D03*
X241339D03*
X244488D03*
X247638D03*
X250788D03*
X253937D03*
X257087D03*
X260237D03*
X263386D03*
X266536D03*
X269685D03*
X272835D03*
X275985D03*
X279134D03*
X282284D03*
X285433D03*
X288583D03*
X304331D03*
X307481D03*
X310630D03*
X313780D03*
X316929D03*
X320079D03*
X323229D03*
X326378D03*
X329528D03*
X332677D03*
X335827D03*
X338977D03*
X342126D03*
X345276D03*
X348426D03*
X351575D03*
X354725D03*
X357874D03*
X361024D03*
X364174D03*
X367323D03*
X370473D03*
X373622D03*
X376772D03*
X379922D03*
X383071D03*
X386221D03*
X389370D03*
X392520D03*
X395670D03*
X398819D03*
X401969D03*
X405118D03*
X408268D03*
X411418D03*
X414567D03*
X417717D03*
X420866D03*
X424016D03*
X427166D03*
X430315D03*
X433465D03*
X436614D03*
X439764D03*
X532678D03*
X535827D03*
X538977D03*
X542126D03*
X545276D03*
X548426D03*
X551575D03*
X554725D03*
X557874D03*
X561024D03*
X564174D03*
X567323D03*
X570473D03*
X573623D03*
X576772D03*
X579922D03*
X583071D03*
X586221D03*
X589371D03*
X592520D03*
X595670D03*
X598819D03*
X601969D03*
X605119D03*
X608268D03*
X611418D03*
X614567D03*
X617717D03*
X620867D03*
X624016D03*
X627166D03*
X630315D03*
X633465D03*
X636615D03*
X639764D03*
X642914D03*
X646063D03*
X649213D03*
X652363D03*
X655512D03*
X658662D03*
X661811D03*
X664961D03*
X668111D03*
X671260D03*
X674410D03*
X677560D03*
X680709D03*
X683859D03*
X687008D03*
X690158D03*
X693308D03*
X696457D03*
X699607D03*
X702756D03*
X705906D03*
X721654D03*
X724804D03*
X727953D03*
X731103D03*
X734252D03*
X737402D03*
X740552D03*
X743701D03*
X746851D03*
X750000D03*
X753150D03*
X756300D03*
X759449D03*
X762599D03*
X765749D03*
X768898D03*
X772048D03*
X775197D03*
X778347D03*
X781497D03*
X784646D03*
X787796D03*
X790945D03*
X794095D03*
X797245D03*
X800394D03*
X803544D03*
X806693D03*
X809843D03*
X812993D03*
X816142D03*
X819292D03*
X822441D03*
X825591D03*
X828741D03*
X831890D03*
X835040D03*
X838189D03*
X841339D03*
X844489D03*
X847638D03*
X850788D03*
X853937D03*
X857087D03*
X1028741D03*
X1031890D03*
X1035040D03*
X1038189D03*
X1041339D03*
X1044489D03*
X1047638D03*
X1050788D03*
X1053937D03*
X1057087D03*
X1060237D03*
X1063386D03*
X1066536D03*
X1069686D03*
X1072835D03*
X1075985D03*
X1079134D03*
X1082284D03*
X1085434D03*
X1088583D03*
X1091733D03*
X1094882D03*
X1098032D03*
X1101182D03*
X1104331D03*
X1107481D03*
X1110630D03*
X1113780D03*
X1116930D03*
X1120079D03*
X1123229D03*
X1126378D03*
X1129528D03*
X1132678D03*
X1135827D03*
X1138977D03*
X1142126D03*
X1145276D03*
X1148426D03*
X1151575D03*
X1154725D03*
X1157874D03*
X1161024D03*
X1164174D03*
X1167323D03*
X1170473D03*
X1173623D03*
X1176772D03*
X1179922D03*
X1183071D03*
X1186221D03*
X1189371D03*
X1192520D03*
X1195670D03*
X1198819D03*
X1201969D03*
X1217717D03*
X1220867D03*
X1224016D03*
X1227166D03*
X1230315D03*
X1233465D03*
X1236615D03*
X1239764D03*
X1242914D03*
X1246063D03*
X1249213D03*
X1252363D03*
X1255512D03*
X1258662D03*
X1261812D03*
X1264961D03*
X1268111D03*
X1271260D03*
X1274410D03*
X1277560D03*
X1280709D03*
X1283859D03*
X1287008D03*
X1290158D03*
X1293308D03*
X1296457D03*
X1299607D03*
X1302756D03*
X1305906D03*
X1309056D03*
X1312205D03*
X1315355D03*
X1318504D03*
X1321654D03*
X1324804D03*
X1327953D03*
X1331103D03*
X1334252D03*
X1337402D03*
X1340552D03*
X1343701D03*
X1346851D03*
X1350000D03*
X1353150D03*
G54D32*
X72900Y729500D03*
X148500Y521700D03*
X158500Y522700D03*
X221000Y518200D03*
X294500Y145700D03*
X290178Y732631D03*
X273500Y732600D03*
X322178Y732631D03*
X306178D03*
X503178Y784631D03*
X487000Y784600D03*
X488500Y808200D03*
X535178Y784631D03*
X519069Y785167D03*
X556531Y361280D03*
X560531D03*
X635500Y363300D03*
X645663Y234708D03*
X639000Y363300D03*
X847500Y762100D03*
X862678Y762131D03*
X892678Y761631D03*
X1204335Y134891D03*
X1207745Y134890D03*
X1266432Y151337D03*
X1269834D03*
X1307400Y690100D03*
X1306000Y713200D03*
X1324900Y690100D03*
X1341400D03*
G54D23*
X57700Y499200D03*
X53600D03*
X92360Y566710D03*
X110000Y291200D03*
X145000Y461700D03*
X141000D03*
X150150Y452690D03*
X155680Y452630D03*
X146150Y452690D03*
X137000Y461200D03*
X140500Y452690D03*
X164000Y461200D03*
X161500Y501700D03*
X164000Y795200D03*
X160000D03*
X182300Y411300D03*
X193650Y458522D03*
X189650D03*
X197500Y574200D03*
X191500Y584700D03*
X199500Y716200D03*
X171300Y739500D03*
X167300D03*
X199500Y771700D03*
X200500Y411700D03*
X230571Y469717D03*
X221000Y538200D03*
X229000Y521700D03*
X225000Y529200D03*
X229000D03*
X201500Y574200D03*
X203500Y716200D03*
Y771700D03*
X237500Y135700D03*
X245500D03*
X241500D03*
X235100Y466200D03*
X251800Y466400D03*
X274406Y723098D03*
X278406D03*
X286906Y772098D03*
X299164Y772291D03*
X295079Y772050D03*
X303406Y772098D03*
X323406Y771098D03*
X319406D03*
X476200Y380400D03*
X480200D03*
X487906Y775098D03*
X491906D03*
X500406Y824098D03*
X512679Y824050D03*
X508579D03*
X516906Y824098D03*
X524906D03*
X528906D03*
X711510Y13880D03*
X715380Y25480D03*
X715130Y49100D03*
X837000Y778200D03*
X852400Y87500D03*
X871000Y82200D03*
X848100Y87600D03*
X856906Y752098D03*
X860906D03*
X869906Y801098D03*
X893100Y38100D03*
X875000Y93200D03*
X879500D03*
X884000D03*
X888500D03*
X893000D03*
X897500D03*
X902000D03*
X906500D03*
X882049Y803660D03*
X877949D03*
X886276Y803708D03*
X894406Y801098D03*
X898406D03*
X911000Y93200D03*
X915500D03*
X920000D03*
X933500D03*
X929000D03*
X924500D03*
X938000D03*
X956000D03*
X990552Y104500D03*
X986552D03*
X1003100D03*
X999000D03*
X987039Y157215D03*
X1040140Y10963D03*
X1035830Y10919D03*
X1044147Y13790D03*
X1049161Y11807D03*
X1073250Y32450D03*
X1046950Y36565D03*
X1051450D03*
X1068750Y20450D03*
X1065475Y52273D03*
X1061342Y75796D03*
X1293500Y277700D03*
X1302128Y680567D03*
X1306128D03*
X1314628Y729567D03*
X1325500Y729700D03*
X1334128Y729567D03*
X1338128D03*
X1355000Y283200D03*
X1359000D03*
X1351000D03*
G54D42*
X162200Y512500D03*
Y509000D03*
Y505500D03*
X162219Y521720D03*
X162200Y516000D03*
X181700Y443300D03*
X612263Y253108D03*
X639700Y355600D03*
Y359600D03*
X874348Y764898D03*
X1005412Y35919D03*
G54D60*
X883500Y36100D03*
X879500Y44900D03*
X887500D03*
G54D51*
X273162Y749719D03*
X275722D03*
X278282D03*
Y743219D03*
X273162D03*
X290440Y749750D03*
X293000D03*
X295560D03*
Y743250D03*
X290440D03*
X306440Y749750D03*
X309000D03*
X311560D03*
Y743250D03*
X306440D03*
X322440Y749750D03*
X325000D03*
X327560D03*
Y743250D03*
X322440D03*
X486662Y801719D03*
X489222D03*
X491782D03*
Y795219D03*
X486662D03*
X535440Y801750D03*
Y795250D03*
X519440Y801750D03*
X522000D03*
X524560D03*
Y795250D03*
X519440D03*
X503440Y801750D03*
X506000D03*
X508560D03*
Y795250D03*
X503440D03*
X538000Y801750D03*
X540560D03*
Y795250D03*
X873060Y37350D03*
X870500D03*
X867940D03*
Y43850D03*
X873060D03*
X862940Y778750D03*
X865500D03*
X868060D03*
Y772250D03*
X862940D03*
X846662Y779219D03*
X849222D03*
X851782D03*
Y772719D03*
X846662D03*
X892940Y778750D03*
X895500D03*
X898060D03*
Y772250D03*
X892940D03*
X876940Y778750D03*
X879500D03*
X882060D03*
Y772250D03*
X876940D03*
X1307662Y706719D03*
X1310222D03*
X1307662Y700219D03*
X1312782Y706719D03*
Y700219D03*
X1341662Y707219D03*
X1344222D03*
X1341662Y700719D03*
X1325162Y707219D03*
X1327722D03*
X1330282D03*
Y700719D03*
X1325162D03*
X1376734Y175745D03*
X1374174D03*
X1371614D03*
Y182245D03*
X1376734D03*
X1346782Y707219D03*
Y700719D03*
G54D33*
X122165Y142874D03*
X173897D03*
G54D24*
X57700Y495800D03*
X53600D03*
X92360Y563310D03*
X110000Y287800D03*
X145000Y458300D03*
X141000D03*
X150150Y449290D03*
X155680Y449230D03*
X146150Y449290D03*
X137000Y457800D03*
X140500Y449290D03*
X164000Y457800D03*
X161500Y498300D03*
X164000Y791800D03*
X160000D03*
X182300Y407900D03*
X193650Y455122D03*
X189650D03*
X197500Y570800D03*
X191500Y581300D03*
X199500Y712800D03*
X171300Y736100D03*
X167300D03*
X199500Y768300D03*
X200500Y408300D03*
X230571Y466317D03*
X221000Y534800D03*
X229000Y518300D03*
X225000Y525800D03*
X229000D03*
X201500Y570800D03*
X203500Y712800D03*
Y768300D03*
X237500Y132300D03*
X245500D03*
X241500D03*
X235100Y462800D03*
X251800Y463000D03*
X274406Y719698D03*
X278406D03*
X286906Y768698D03*
X299164Y768891D03*
X295079Y768650D03*
X303406Y768698D03*
X323406Y767698D03*
X319406D03*
X476200Y377000D03*
X480200D03*
X487906Y771698D03*
X491906D03*
X500406Y820698D03*
X512679Y820650D03*
X508579D03*
X516906Y820698D03*
X524906D03*
X528906D03*
X711510Y10480D03*
X715380Y22080D03*
X715130Y45700D03*
X837000Y774800D03*
X852400Y84100D03*
X871000Y78800D03*
X848100Y84200D03*
X856906Y748698D03*
X860906D03*
X869906Y797698D03*
X893100Y34700D03*
X875000Y89800D03*
X879500D03*
X884000D03*
X888500D03*
X893000D03*
X897500D03*
X902000D03*
X906500D03*
X882049Y800260D03*
X877949D03*
X886276Y800308D03*
X894406Y797698D03*
X898406D03*
X911000Y89800D03*
X915500D03*
X920000D03*
X933500D03*
X929000D03*
X924500D03*
X938000D03*
X956000D03*
X990552Y101100D03*
X986552D03*
X1003100D03*
X999000D03*
X987039Y153815D03*
X1035830Y7519D03*
X1040140Y7563D03*
X1044147Y10390D03*
X1049161Y8407D03*
X1073250Y29050D03*
X1046950Y33165D03*
X1051450D03*
X1068750Y17050D03*
X1065475Y48873D03*
X1061342Y72396D03*
X1293500Y274300D03*
X1302128Y677167D03*
X1306128D03*
X1314628Y726167D03*
X1325500Y726300D03*
X1334128Y726167D03*
X1338128D03*
X1355000Y279800D03*
X1359000D03*
X1351000D03*
G54D15*
X29000Y616000D03*
X63500Y353960D03*
X54903Y447003D03*
X68100Y264700D03*
X98588Y281650D03*
X96304Y287616D03*
X70124Y279374D03*
X78500Y277900D03*
X92907Y280765D03*
X67796Y470042D03*
X86363Y479563D03*
X95742Y490870D03*
X86787Y494553D03*
X66854Y507824D03*
X68600Y494400D03*
X88700Y524900D03*
X88565Y532410D03*
X70515Y538726D03*
X68567Y531405D03*
X88278Y548853D03*
X73100Y553100D03*
X88338Y553955D03*
X85500Y807700D03*
X116906Y283244D03*
X111000Y324200D03*
X102457Y347690D03*
X132204Y434627D03*
X114818Y433528D03*
X128280Y476120D03*
X105728Y471628D03*
X103500Y465026D03*
X127142Y459404D03*
X107889Y457989D03*
X116204Y474504D03*
X131718Y498682D03*
X128450Y481470D03*
X117771Y499896D03*
X117867Y488950D03*
X128100Y507700D03*
X100063Y498972D03*
X103055Y503417D03*
X106818Y513350D03*
X99221Y509408D03*
X106037Y507711D03*
X106900Y488923D03*
X114000Y483700D03*
X105555Y483119D03*
X116439Y547024D03*
X102075Y529701D03*
X130200Y517000D03*
X106575Y518876D03*
X107341Y528856D03*
X99768Y518303D03*
X113757Y520886D03*
X105136Y535172D03*
X113900Y533666D03*
X102326Y540322D03*
X100270Y545196D03*
X122048Y541693D03*
X115100Y541700D03*
X123100Y547800D03*
X100350Y550196D03*
X105851Y637000D03*
X120500Y697500D03*
X122167Y731990D03*
X99700Y732300D03*
X103800Y727700D03*
X108200Y775800D03*
X112700Y775300D03*
Y770800D03*
X108200D03*
X103700D03*
Y775800D03*
Y766300D03*
X108200D03*
X112700D03*
X110900Y779200D03*
X122200Y831700D03*
X158170Y314302D03*
X162670D03*
X153670D03*
X156170Y318302D03*
X160670D03*
X134587Y443980D03*
X137136Y422798D03*
X165000Y468000D03*
X157500D03*
X139500Y466500D03*
X134500Y466000D03*
X157500Y458000D03*
Y463000D03*
X133440Y449150D03*
X132959Y460709D03*
X159434Y475345D03*
X133589Y477613D03*
X136272Y496478D03*
X137600Y501338D03*
X150100Y494700D03*
X164371Y494680D03*
X165864Y533933D03*
X143500Y622500D03*
X137194Y727551D03*
X164378Y778459D03*
X159774Y785777D03*
X164442Y802359D03*
X159838Y813369D03*
X148000Y833500D03*
X175430Y261054D03*
X173277Y315920D03*
X167423Y341376D03*
X188215Y333962D03*
X182855Y337950D03*
X176854Y332347D03*
X187361Y342183D03*
X181838Y332783D03*
X178692Y352383D03*
X197937Y384347D03*
X197713Y431418D03*
X199900Y420100D03*
X175317Y416683D03*
X181400Y415300D03*
X182000Y466000D03*
X177000D03*
X171000Y468000D03*
X169000Y463000D03*
Y458000D03*
X187928Y473629D03*
X179192Y471349D03*
X190675Y468551D03*
X181328Y460701D03*
X199880Y498149D03*
X198000Y493500D03*
X166608Y501664D03*
X184535Y502910D03*
X194148Y501205D03*
X187300Y486900D03*
X169514Y492829D03*
X199809Y485199D03*
X178000Y542000D03*
X173000Y547500D03*
X178000Y547000D03*
X167000Y545500D03*
X168599Y527221D03*
X173000Y542500D03*
X173618Y516881D03*
X181811Y524978D03*
X188978Y524513D03*
X185355Y537874D03*
X173000Y552500D03*
X193600Y569800D03*
X186416Y573231D03*
X193500Y628000D03*
X199379Y698698D03*
X171631Y722694D03*
X167027Y730499D03*
X199411Y721528D03*
X171729Y747695D03*
X199378Y752617D03*
X167125Y759093D03*
X199410Y790376D03*
X169840Y836660D03*
X174265Y828735D03*
X224500Y170500D03*
Y174700D03*
Y166300D03*
Y178900D03*
X220384Y178059D03*
X223000Y184000D03*
Y188500D03*
X225000Y192500D03*
X229200D03*
X215968Y389018D03*
X214888Y425445D03*
X221699Y428056D03*
X202469Y429873D03*
X205100Y413700D03*
X202185Y462653D03*
X204319Y479895D03*
X206487Y475373D03*
X218774Y452245D03*
X224548Y470077D03*
X206285Y457550D03*
X218425D03*
X223334Y458504D03*
X210828Y469403D03*
X205397Y489870D03*
X232600Y535000D03*
X201400Y532400D03*
X205000Y521500D03*
X217291Y524970D03*
X201900Y525500D03*
X222500Y514500D03*
X222700Y546500D03*
X206200Y530500D03*
X201429Y566997D03*
X222800Y562100D03*
X210510Y562800D03*
X203983Y706502D03*
X204015Y733445D03*
X204186Y762392D03*
X204014Y779192D03*
X217104Y796396D03*
X214649Y802351D03*
X212841Y807659D03*
X218937Y791063D03*
X249530Y132250D03*
X259500Y138500D03*
X236807Y140322D03*
X261500Y173500D03*
X253000Y166500D03*
X258700D03*
X262900D03*
X236500Y147500D03*
X243000Y176500D03*
X243500Y166500D03*
Y162000D03*
Y157000D03*
X239500Y160500D03*
X261500Y179000D03*
Y184500D03*
X261000Y190500D03*
X258225Y193963D03*
X266500Y184500D03*
Y190500D03*
X243000Y181000D03*
Y186000D03*
X266200Y243500D03*
X251700Y429200D03*
X241446Y452004D03*
X247661Y473600D03*
X247473Y455600D03*
X260500Y486800D03*
X259800Y492500D03*
X233701Y522611D03*
X262500Y532012D03*
X239900Y600100D03*
X240000Y608600D03*
Y604400D03*
X241521Y654021D03*
X248890Y708110D03*
X255968Y706032D03*
X249797Y701703D03*
X259633Y715867D03*
X260816Y710184D03*
X254212Y712288D03*
X267011Y718817D03*
X257728Y722272D03*
X263500Y748700D03*
X268500Y140500D03*
X271000Y184500D03*
X273800Y240000D03*
X299800Y305500D03*
X285700Y578165D03*
X285900Y583165D03*
X285606Y588172D03*
X267540Y585155D03*
X273134Y593265D03*
X270430Y725738D03*
X279045Y729078D03*
X293738Y729123D03*
X299500Y736000D03*
X283004Y739009D03*
X278500Y768500D03*
X290830Y768755D03*
X285000Y757000D03*
X297500D03*
X275900Y755951D03*
X334755Y141755D03*
X329500Y192500D03*
X328000Y197400D03*
X334500Y197500D03*
Y192500D03*
X321708Y371677D03*
X321454Y351196D03*
X330000Y496213D03*
X329913Y714413D03*
X321500Y706500D03*
X328331Y708331D03*
X306471Y722269D03*
X318162Y729949D03*
X302000Y730500D03*
X332500Y739500D03*
X315531Y734807D03*
X307400Y765738D03*
X327373Y765761D03*
X317453Y752192D03*
X303000Y756500D03*
X329575Y758230D03*
X315100Y757400D03*
X344000Y197500D03*
X339500D03*
X344000Y192500D03*
X339500D03*
X359061Y335014D03*
X338725Y481514D03*
X357500Y561500D03*
X362533Y808033D03*
X364759Y815759D03*
X360807Y799807D03*
X417988Y813088D03*
X449500Y85000D03*
X480533Y363869D03*
X475782Y371442D03*
X480960Y388964D03*
X476010Y399971D03*
X485724Y779993D03*
X495307Y763932D03*
X495824Y756449D03*
X487949Y760641D03*
X487744Y752436D03*
X498500Y809000D03*
X477000Y804000D03*
X481600Y796800D03*
X496000Y788000D03*
X492278Y820500D03*
X481000Y818000D03*
X520910Y124390D03*
X515220Y126440D03*
X531900Y155800D03*
X523242Y196195D03*
X529154Y255014D03*
X536081Y304376D03*
X536809Y298789D03*
X525785Y362796D03*
X537000Y700500D03*
X504169Y774643D03*
X518328Y781467D03*
X531500Y778600D03*
X514298Y784745D03*
X516500Y808000D03*
X530012Y803025D03*
X510500Y808500D03*
X527948Y809620D03*
X508700Y784700D03*
X528500Y788000D03*
X521000Y820000D03*
X504241Y820278D03*
X532506Y820000D03*
X538158Y156255D03*
X546391Y208718D03*
X548656Y229162D03*
X565063Y256608D03*
Y247608D03*
Y252108D03*
X560318Y267199D03*
Y272199D03*
X560418Y278299D03*
Y283799D03*
Y289299D03*
X560318Y295699D03*
X568663Y288740D03*
X553563Y306108D03*
Y310608D03*
X557904Y327115D03*
X562123Y319158D03*
X553455Y314807D03*
X553463Y319108D03*
X557863D03*
X554300Y368300D03*
X545500Y783500D03*
X537500Y817000D03*
X546200Y799800D03*
X546000Y793000D03*
X577336Y125424D03*
X573055Y121869D03*
X603163Y220858D03*
X580200Y224000D03*
X596500Y226100D03*
X591861Y232396D03*
X576200Y238400D03*
X605063Y257608D03*
X585515Y276459D03*
X583009Y264117D03*
X585351Y269292D03*
X587984Y246148D03*
X587980Y251975D03*
X589164Y264150D03*
X582738Y273300D03*
X587063Y257608D03*
X582976Y246148D03*
X583286Y251974D03*
X582682Y257614D03*
X602463Y284008D03*
X589400Y308626D03*
X585737Y289608D03*
Y283108D03*
X582683Y279618D03*
X582411Y286589D03*
X582363Y293408D03*
X580563Y308608D03*
X583391Y298870D03*
X583282Y303091D03*
X616614Y123871D03*
X611642Y123340D03*
X607812Y149121D03*
X612812Y149084D03*
X609777Y158860D03*
X611563Y278108D03*
X607563Y265608D03*
X607463Y270608D03*
X607563Y261108D03*
X609063Y255608D03*
X607563Y276108D03*
Y282108D03*
Y287608D03*
Y293608D03*
X607519Y299497D03*
X611563Y290108D03*
Y284608D03*
X632900Y339700D03*
X655000Y125360D03*
X649692Y125160D03*
X643518Y125457D03*
X656500Y139300D03*
X666593Y226677D03*
X662593Y223677D03*
X658093D03*
X670063Y274708D03*
X669633Y259148D03*
X670465Y266585D03*
X672100Y299800D03*
X646600Y363400D03*
X643538Y803500D03*
X641000Y816500D03*
X646800Y811500D03*
X691100Y168238D03*
X704537Y221492D03*
X678063Y238108D03*
X673063D03*
X672927Y219677D03*
X677927D03*
X686063Y230108D03*
X696800Y237900D03*
X682763Y238008D03*
X686063Y224608D03*
X703600Y233700D03*
X687253Y237878D03*
X691753D03*
X698300Y226500D03*
X693800D03*
X689623Y269648D03*
X694963Y269608D03*
X689723Y274748D03*
X694223D03*
X679723D03*
X684223D03*
X690233Y255748D03*
X695000Y255800D03*
X690133Y260348D03*
X694633D03*
X680133Y259148D03*
X684633D03*
X674563Y274708D03*
X674133Y259148D03*
X695963Y302308D03*
Y297808D03*
Y293308D03*
X690663Y287608D03*
Y292108D03*
X691400Y310000D03*
X677000Y299900D03*
X682063Y299108D03*
X683800Y295000D03*
X684063Y285908D03*
Y290408D03*
X691487Y798987D03*
X693243Y804943D03*
X688212Y791912D03*
X695049Y811349D03*
X731800Y166000D03*
X712337Y207792D03*
X706937Y203092D03*
X736100Y197200D03*
X712137Y213292D03*
Y219392D03*
X725300Y228700D03*
X730300D03*
X711300D03*
X716300D03*
X716900Y233800D03*
X721400D03*
X730400D03*
X725900D03*
X735400D03*
X707900D03*
X712400D03*
X738800Y272000D03*
Y265500D03*
Y258000D03*
Y251500D03*
X706800Y272500D03*
Y265500D03*
Y258000D03*
Y252000D03*
X715300Y272000D03*
Y265500D03*
Y258000D03*
Y251500D03*
X724300Y272000D03*
Y265500D03*
Y258000D03*
Y251500D03*
X732300Y272000D03*
Y265500D03*
Y258000D03*
Y251500D03*
X706800Y290700D03*
X718800Y291000D03*
X714300D03*
X707363Y298108D03*
X718863Y295908D03*
X714363D03*
X723300Y291000D03*
X732300D03*
X727800D03*
X723363Y295908D03*
X732363D03*
X727863D03*
X737300Y291000D03*
X741600Y34439D03*
X751871Y175034D03*
X755200Y223800D03*
X756200Y299800D03*
X799459Y772175D03*
X815976Y32276D03*
X838881Y27195D03*
X833246Y24741D03*
X826141Y21594D03*
X819052Y23633D03*
X811937Y41381D03*
X827727Y43554D03*
X825500Y697000D03*
X817405Y779905D03*
X808584Y776584D03*
X831500Y774750D03*
X836300Y783300D03*
X865600Y-1700D03*
X853500Y-2100D03*
X863500Y28000D03*
X848545Y24961D03*
X843545Y25012D03*
X871800Y15309D03*
X850900Y16200D03*
X848623Y74557D03*
X865004Y49379D03*
X866000Y82500D03*
X859000Y86500D03*
X866919Y92419D03*
X858821Y75500D03*
X853500Y257000D03*
X850799Y743301D03*
X872500Y728500D03*
X844500Y750000D03*
X851500Y753000D03*
X872617Y750235D03*
X864366Y758100D03*
X856576Y767771D03*
X867640Y761880D03*
X861500Y797000D03*
X853500Y817362D03*
X874033Y797475D03*
X864000Y814500D03*
X858020Y786180D03*
X840960Y785260D03*
X864147Y785093D03*
X863500Y823338D03*
X845500Y820500D03*
X878320Y4350D03*
X888200Y30500D03*
X882429Y54551D03*
X905488Y48573D03*
X902169Y97919D03*
X894533Y100933D03*
X875070Y104670D03*
X894850Y112060D03*
X903920Y137780D03*
X898000Y117000D03*
X908020Y153340D03*
X903937Y145666D03*
X903970Y157478D03*
X895232Y186459D03*
X885000Y297000D03*
X898500Y499000D03*
X880889Y613611D03*
X875252Y623748D03*
X896000Y686000D03*
X884700Y708000D03*
X892100Y694000D03*
X881200Y713500D03*
X888550Y702000D03*
X887500Y731500D03*
X879815Y742296D03*
X886800Y759500D03*
X878578Y761050D03*
X899800Y753000D03*
X898566Y761430D03*
X886500Y765000D03*
X890500Y796638D03*
X888000Y789000D03*
X874800Y786800D03*
X900000Y786000D03*
X882590Y787130D03*
X921300Y74700D03*
X918100Y71900D03*
X929464Y49420D03*
X925022Y42909D03*
X929713Y44849D03*
X925300Y47100D03*
X926500Y60050D03*
X930500Y57500D03*
X910945Y49234D03*
X938600Y99500D03*
X915315Y97565D03*
X939384Y106513D03*
X915926Y102676D03*
X908676Y99926D03*
X911800Y141750D03*
X919650Y137800D03*
X915750Y133900D03*
X912200Y112300D03*
X940051Y113222D03*
X934700Y114200D03*
X911817Y149617D03*
X911820Y157500D03*
X915790Y161420D03*
X919685Y149606D03*
X915750Y145650D03*
Y153500D03*
X919700Y157500D03*
X927559Y153543D03*
X920800Y143400D03*
X923620Y161450D03*
X914700Y281100D03*
X976066Y26581D03*
X971466Y26681D03*
X947000Y71500D03*
X975086Y61900D03*
X970000Y61050D03*
X960244Y64888D03*
X952900Y98900D03*
X967263Y100000D03*
Y105000D03*
X975004Y105097D03*
Y100097D03*
X960500Y105000D03*
X953000Y104500D03*
X944300Y98500D03*
X960500Y100000D03*
X960000Y95000D03*
X959793Y75788D03*
X970866Y137795D03*
X974803Y141732D03*
X949700Y112900D03*
X959055Y129921D03*
X974803Y133858D03*
X966929D03*
X955118Y141732D03*
X959055Y137795D03*
X949987Y131571D03*
X948058Y136248D03*
X974803Y157480D03*
X970866Y161417D03*
X955118Y149606D03*
X959055Y145669D03*
X970866Y153543D03*
X966929Y149606D03*
X970866Y145669D03*
X959055Y161417D03*
Y153543D03*
X962992Y157480D03*
X951181Y153543D03*
X945030Y156121D03*
X944300Y271000D03*
X968500Y383500D03*
X985880Y41686D03*
X980566Y26581D03*
X1005774Y31854D03*
X1005750Y19788D03*
X985880Y46086D03*
Y50586D03*
X980000Y44000D03*
X996251Y45701D03*
X982000Y100000D03*
Y105000D03*
X994700Y108600D03*
X982677Y141732D03*
X990551Y133858D03*
X982677D03*
X984760Y112189D03*
X982700Y149600D03*
X978740Y153543D03*
X982632Y157480D03*
X978740Y161417D03*
X991300Y145800D03*
X991608Y153979D03*
X1000000Y187000D03*
X980000Y281300D03*
X1035323Y-758D03*
X1031991Y22473D03*
X1036989Y22307D03*
X1036013Y27318D03*
X1033971Y34914D03*
X1031474Y9728D03*
X1020676Y53563D03*
X1037815Y104700D03*
X1016500Y101050D03*
X1041249Y112300D03*
X1030883Y112238D03*
X1066272Y1949D03*
X1044391Y-1209D03*
X1069394Y13018D03*
X1052744Y48446D03*
X1072167Y49782D03*
X1069889Y45154D03*
X1048000Y815000D03*
X1088503Y3601D03*
X1085500Y-3000D03*
X1086715Y27686D03*
X1080017Y27022D03*
X1086500Y280000D03*
X1177600Y241200D03*
X1173400D03*
X1166400Y234300D03*
X1170600D03*
X1175700D03*
X1171300Y215700D03*
X1166300D03*
X1175999D03*
X1177200Y248200D03*
X1173000D03*
X1177300Y254400D03*
X1173100D03*
X1176300Y261500D03*
X1171200D03*
X1167000D03*
Y254000D03*
X1168000Y280000D03*
X1173000D03*
X1177500D03*
X1171747Y814500D03*
X1176738Y806500D03*
X1168607Y834500D03*
X1203100Y241100D03*
X1198900D03*
X1207900D03*
X1182400Y241200D03*
X1197900Y234300D03*
X1207400D03*
X1203200D03*
X1179900D03*
X1188900D03*
X1184700D03*
X1193700D03*
X1190300Y215700D03*
X1185300D03*
X1208800D03*
X1203800D03*
X1180601D03*
X1199300D03*
X1194500D03*
X1182000Y248200D03*
X1202600Y254100D03*
X1198400D03*
X1207400D03*
X1202500Y247500D03*
X1198300D03*
X1207300D03*
X1182100Y254400D03*
X1203800Y261500D03*
X1208000D03*
X1194300D03*
X1198500D03*
X1185300D03*
X1189500D03*
X1180500D03*
X1187000Y280000D03*
X1192000D03*
X1205500D03*
X1210500D03*
X1182500D03*
X1201000D03*
X1196200D03*
X1198134Y420766D03*
X1179723Y418777D03*
X1229000Y210500D03*
X1242500Y209000D03*
X1232000Y194500D03*
X1237000D03*
X1226500Y201500D03*
Y194500D03*
X1244500D03*
X1212900Y234300D03*
X1214800Y215700D03*
X1233900Y240700D03*
X1239900D03*
X1244900D03*
X1228900D03*
X1228500Y235000D03*
X1234000D03*
X1240000D03*
X1245000D03*
X1214000Y261500D03*
X1233800Y246600D03*
X1239800D03*
X1244800D03*
X1228800D03*
X1229000Y252000D03*
X1245000D03*
X1240000D03*
X1234000D03*
X1227000Y279000D03*
X1242000D03*
X1232000Y292000D03*
X1237000D03*
X1227000Y285500D03*
X1244500Y292000D03*
X1242500Y645000D03*
X1236000Y814000D03*
X1269500Y161000D03*
X1247500Y209000D03*
X1252500Y194500D03*
X1263000Y210307D03*
X1257500Y194500D03*
X1263000Y202000D03*
X1262500Y194500D03*
X1255900Y240700D03*
X1249900D03*
X1262500Y235000D03*
X1250000D03*
X1256000D03*
X1261000Y230000D03*
X1255800Y246600D03*
X1249800D03*
X1262000Y252000D03*
X1256000D03*
X1250000D03*
X1247000Y279000D03*
X1262500Y279500D03*
X1252000Y292000D03*
X1257000D03*
X1262500Y286000D03*
X1255000Y323000D03*
X1274030Y339470D03*
X1264820Y356000D03*
X1273500Y406500D03*
X1270000Y487500D03*
X1269000Y609000D03*
X1284505Y308395D03*
X1280836Y338164D03*
X1295000Y338000D03*
X1307500Y340500D03*
X1293280Y345770D03*
X1289960Y349900D03*
X1299000Y347500D03*
X1298500Y376500D03*
X1312839Y384339D03*
X1305500Y379500D03*
X1305432Y622932D03*
X1296264Y645191D03*
X1291800Y637751D03*
X1292000Y667000D03*
X1298017Y684000D03*
X1303709Y688956D03*
X1298000Y703500D03*
X1298500Y734838D03*
X1305650Y725500D03*
X1295714Y716714D03*
X1327782Y192579D03*
Y200579D03*
Y207579D03*
X1328411Y237679D03*
X1327782Y215579D03*
Y221579D03*
X1327841Y228639D03*
X1332683Y240409D03*
X1328356Y242091D03*
X1327736Y271358D03*
X1328317Y246291D03*
X1332683Y244609D03*
Y248809D03*
X1325500Y289400D03*
X1314422Y638422D03*
X1326250Y669550D03*
X1318117Y680886D03*
X1343000Y681000D03*
X1331000Y658200D03*
X1330000Y672162D03*
X1333052Y686020D03*
X1319500Y690000D03*
X1337338Y712709D03*
X1322300Y713500D03*
X1315000Y714000D03*
X1333639Y716074D03*
X1317500Y695000D03*
X1334195Y694005D03*
X1318228Y725500D03*
X1330000Y724500D03*
X1344237Y721833D03*
X1342000Y726500D03*
X1338128Y738000D03*
X1320500Y719888D03*
X1324000Y763500D03*
X1340500Y751500D03*
X1379473Y163528D03*
X1368540Y169284D03*
X1366672Y210312D03*
X1360844Y210366D03*
X1355944Y210313D03*
X1351525Y207104D03*
X1351545Y202879D03*
Y198575D03*
X1353908Y194867D03*
X1378115Y189144D03*
X1374000Y192500D03*
Y188300D03*
Y196700D03*
X1378500Y198000D03*
X1378115Y193344D03*
X1365804Y189733D03*
X1370000Y216500D03*
X1375196Y217203D03*
X1367042Y223895D03*
X1375359Y230110D03*
X1372000Y240500D03*
X1351777Y227823D03*
X1360644Y223881D03*
X1350987Y236754D03*
X1351668Y232125D03*
X1355644Y223881D03*
X1351899Y219598D03*
X1351954Y215268D03*
X1354989Y239016D03*
X1350950Y241000D03*
X1349639Y211374D03*
X1349298Y223737D03*
X1372000Y245300D03*
Y249500D03*
X1354500Y271000D03*
X1355209Y263791D03*
X1355050Y247300D03*
X1350950Y246100D03*
X1364000Y299500D03*
X1351500Y671200D03*
X1355000Y716000D03*
X1352000Y708500D03*
Y698000D03*
X1353500Y758500D03*
X1383164Y168943D03*
X1382500Y193500D03*
Y188000D03*
G54D70*
G01X278282Y749719D02*
X280281D01*
X281500Y748500D01*
G01X702300Y254500D02*
X704029D01*
G01X702300Y251500D02*
X704029D01*
G01X702300Y260500D02*
X704029D01*
G01X702300Y257500D02*
X704029D01*
G01X702300Y272500D02*
X704029D01*
G01X702300Y269500D02*
X704029D01*
G01X702300Y266500D02*
X704029D01*
G01X702300Y263500D02*
X704029D01*
G01X699900Y254500D02*
X698645D01*
G01X699900Y251500D02*
X698645D01*
G01X699900Y260500D02*
X698645D01*
G01X699900Y257500D02*
X698645D01*
G01X699900Y272500D02*
X698645D01*
G01X699900Y269500D02*
X698645D01*
G01X699900Y266500D02*
X698645D01*
G01X699900Y263500D02*
X698645D01*
G01X692763Y281008D02*
Y282537D01*
G01X695763Y281008D02*
Y282537D01*
G01X698763Y281008D02*
Y282537D01*
G01X692763Y278608D02*
Y277137D01*
G01X695763Y278608D02*
Y277137D01*
G01X698763Y278608D02*
Y277137D01*
G01X868060Y778750D02*
X869800D01*
X871000Y777550D01*
Y776500D01*
G01X870400Y785650D02*
Y783728D01*
X874624Y779504D01*
X874626D01*
Y774998D01*
X874000Y774372D01*
Y772000D01*
G01X907900Y127000D02*
X906859D01*
X905906Y127953D01*
G01X907900Y124800D02*
X906690D01*
X905906Y124016D01*
G01X902868Y161468D02*
Y160348D01*
X901969Y159449D01*
G01X890900Y236200D02*
Y237446D01*
X890158Y238188D01*
G01X898060Y778750D02*
Y778767D01*
X900824Y781531D01*
G01X882060Y778750D02*
Y778111D01*
X884671Y775500D01*
G01X892940Y772250D02*
Y765443D01*
X892678Y765181D01*
G01X915793Y127000D02*
X914733D01*
X913780Y127953D01*
G01X911900Y137800D02*
Y137884D01*
X913780Y139764D01*
G01X923600Y127000D02*
X922607D01*
X921654Y127953D01*
G01X931532Y127000D02*
X930481D01*
X929528Y127953D01*
G01X936300Y129900D02*
Y129055D01*
X937402Y127953D01*
G01X938200Y141700D02*
Y140562D01*
X937402Y139764D01*
G01X934100Y129900D02*
Y128588D01*
X933465Y127953D01*
G01X940400Y141700D02*
Y140703D01*
X941339Y139764D01*
G01X909700Y137800D02*
Y135970D01*
X909843Y135827D01*
G01X915793Y124800D02*
X914564D01*
X913780Y124016D01*
G01X923600Y124800D02*
X922438D01*
X921654Y124016D01*
G01X931532Y124800D02*
X930312D01*
X929528Y124016D01*
G01X930250Y157500D02*
Y158727D01*
X929528Y159449D01*
G01X926700Y165338D02*
Y164495D01*
X925591Y163386D01*
G01X925850Y149620D02*
Y151316D01*
X925591Y151575D01*
G01X938350Y157500D02*
Y158501D01*
X937402Y159449D01*
G01X932450Y157500D02*
Y158434D01*
X933465Y159449D01*
G01X923650Y149620D02*
X923636D01*
X921654Y147638D01*
G01X915768Y180068D02*
X916783D01*
X917717Y179134D01*
G01X912900Y181100D02*
Y182191D01*
X913780Y183071D01*
G01X918300Y216550D02*
Y215149D01*
X917717Y214566D01*
G01X912900Y216500D02*
Y215446D01*
X913780Y214566D01*
G01X928600Y220480D02*
Y221512D01*
X929528Y222440D01*
G01X939500Y224400D02*
Y223744D01*
X940804Y222440D01*
X941339D01*
G01X939500Y232300D02*
Y231644D01*
X940830Y230314D01*
X941339D01*
G01X936600Y232300D02*
Y233449D01*
X937402Y234251D01*
G01X928600Y232300D02*
Y233323D01*
X929528Y234251D01*
G01X934400Y236210D02*
Y237253D01*
X933465Y238188D01*
G01X926400Y236210D02*
Y237379D01*
X925591Y238188D01*
G01X934400Y228327D02*
Y229379D01*
X933465Y230314D01*
G01X936600Y224400D02*
Y225575D01*
X937402Y226377D01*
G01X928600Y224400D02*
Y225449D01*
X929528Y226377D01*
G01X974768Y127100D02*
X973687D01*
X972834Y127953D01*
G01X966900Y127100D02*
X965813D01*
X964960Y127953D01*
G01X957400Y126000D02*
Y127639D01*
X957086Y127953D01*
G01X955200Y137800D02*
Y137878D01*
X957086Y139764D01*
G01X953000Y137800D02*
Y135976D01*
X953149Y135827D01*
G01X959600Y126000D02*
Y125351D01*
X959073Y124824D01*
Y124817D01*
X958272Y124016D01*
X957086D01*
G01X966900Y124900D02*
X965844D01*
X964960Y124016D01*
G01X974768Y124900D02*
X973718D01*
X972834Y124016D01*
G01X954368Y161468D02*
Y162167D01*
X953149Y163386D01*
G01X970900Y149600D02*
X970872D01*
X968897Y151575D01*
G01X964050Y161400D02*
Y160359D01*
X964960Y159449D01*
G01X954368Y157468D02*
X955968D01*
X957086Y158586D01*
Y159449D01*
G01X946400Y159200D02*
X948963D01*
X949212Y159449D01*
G01X951000Y149600D02*
X951174D01*
X953149Y151575D01*
G01X948800Y149600D02*
Y151163D01*
X949212Y151575D01*
G01X973100Y149600D02*
Y147904D01*
X972834Y147638D01*
G01X968000Y224400D02*
Y225480D01*
X968897Y226377D01*
G01X968000Y232300D02*
Y233354D01*
X968897Y234251D01*
G01X952300Y236210D02*
Y237339D01*
X953149Y238188D01*
G01X957900Y224400D02*
Y225563D01*
X957086Y226377D01*
G01X950100Y224400D02*
Y225489D01*
X949212Y226377D01*
G01X965800Y224400D02*
Y225537D01*
X964960Y226377D01*
G01X960100Y228327D02*
Y229391D01*
X961023Y230314D01*
G01X950100Y232300D02*
Y233363D01*
X949212Y234251D01*
G01X965800Y232300D02*
Y233411D01*
X964960Y234251D01*
G01X960100Y236210D02*
Y237265D01*
X961023Y238188D01*
G01X968000Y236200D02*
Y237291D01*
X968897Y238188D01*
G01X952300Y228327D02*
Y229465D01*
X953149Y230314D01*
G01X982728Y127100D02*
X981561D01*
X980708Y127953D01*
G01X982500Y137800D02*
Y137972D01*
X980708Y139764D01*
G01X999500Y129900D02*
Y128846D01*
X1000393Y127953D01*
G01X999500Y141768D02*
Y140657D01*
X1000393Y139764D01*
G01X984700Y137800D02*
Y135882D01*
X984645Y135827D01*
G01X982728Y124900D02*
X981592D01*
X980708Y124016D01*
G01X999500Y137768D02*
Y138871D01*
X1000393Y139764D01*
G01X981500Y177150D02*
Y175989D01*
X980708Y175197D01*
G01X999500Y149618D02*
Y148531D01*
X1000393Y147638D01*
G01X999500Y153600D02*
Y154619D01*
X1000393Y155512D01*
G01X1001368Y161468D02*
X1002412D01*
X1004330Y163386D01*
G01X999500Y145668D02*
Y146745D01*
X1000393Y147638D01*
G01X976100Y177150D02*
Y178463D01*
X976771Y179134D01*
G01X981350Y185050D02*
Y183713D01*
X980708Y183071D01*
G01X976050Y216510D02*
Y215287D01*
X976771Y214566D01*
G01X981400Y216505D02*
Y215258D01*
X980708Y214566D01*
G01X1003300Y236200D02*
Y237158D01*
X1004330Y238188D01*
G01X1219300Y221500D02*
X1217792D01*
G01X1219300Y224500D02*
X1217792D01*
G01X1219300Y227500D02*
X1217792D01*
G01X1219300Y230500D02*
X1217792D01*
G01X1219300Y236500D02*
X1217792D01*
G01X1219300Y233500D02*
X1217792D01*
G01X1219300Y239500D02*
X1217792D01*
G01X1219300Y242500D02*
X1217792D01*
G01X1221700Y221500D02*
X1223208D01*
G01X1221700Y224500D02*
X1223208D01*
G01X1221700Y227500D02*
X1223208D01*
G01X1221700Y230500D02*
X1223208D01*
G01X1221700Y236500D02*
X1223208D01*
G01X1221700Y233500D02*
X1223208D01*
G01X1221700Y239500D02*
X1223208D01*
G01X1221700Y242500D02*
X1223208D01*
G01X1219300Y248500D02*
X1217792D01*
G01X1219300Y245500D02*
X1217792D01*
G01X1219300Y251500D02*
X1217792D01*
G01X1219300Y254500D02*
X1217792D01*
G01X1219300Y257500D02*
X1217792D01*
G01X1219300Y260500D02*
X1217792D01*
G01X1219300Y263500D02*
X1217792D01*
G01X1219300Y266500D02*
X1217792D01*
G01X1221700Y248500D02*
X1223208D01*
G01X1221700Y245500D02*
X1223208D01*
G01X1221700Y251500D02*
X1223208D01*
G01X1221700Y254500D02*
X1223208D01*
G01X1221700Y257500D02*
X1223208D01*
G01X1221700Y260500D02*
X1223208D01*
G01X1221700Y263500D02*
X1223208D01*
G01X1221700Y266500D02*
X1223208D01*
G01X1312782Y706719D02*
X1313719D01*
X1315000Y708000D01*
Y708954D01*
X1315546Y709500D01*
G01X1330282Y707219D02*
X1331219D01*
X1333500Y709500D01*
G01X1325162Y700719D02*
Y693912D01*
X1324900Y693650D01*
G01X1346782Y707219D02*
Y711282D01*
X1348500Y713000D01*
G54D43*
X165800Y512500D03*
Y509000D03*
Y505500D03*
X165819Y521720D03*
X165800Y516000D03*
X185300Y443300D03*
X615863Y253108D03*
X643300Y355600D03*
Y359600D03*
X877948Y764898D03*
X1009012Y35919D03*
G54D16*
X39370Y801181D03*
X336417Y21260D03*
X293110Y55906D03*
X336417Y90551D03*
X789850Y236220D03*
Y283464D03*
X1376968Y21260D03*
X1333661Y55906D03*
X1360630Y135826D03*
Y801181D03*
X1376968Y90551D03*
G54D61*
X897500Y141714D03*
X895300D03*
X897500Y137800D03*
X895300D03*
X897500Y133877D03*
X895300D03*
X897500Y129903D03*
X895300D03*
X897500Y153562D03*
X895300D03*
X897500Y149600D03*
X895300D03*
X897500Y145688D03*
X895300D03*
X897500Y161436D03*
X895300D03*
X897500Y157499D03*
X895300D03*
X893100Y236200D03*
X890900D03*
X936300Y129900D03*
X934100D03*
X911900Y137800D03*
X909700D03*
X925850Y149620D03*
X923650D03*
X926700Y165338D03*
X924500D03*
X912900Y181100D03*
X910700D03*
X926700Y185168D03*
X924500D03*
X926700Y204700D03*
X924500D03*
X934800D03*
X932600D03*
X940500D03*
X939500Y224400D03*
Y232300D03*
X936600Y236210D03*
X934400D03*
X928600D03*
X926400D03*
X936600Y228327D03*
X934400D03*
X936600Y220480D03*
X934400D03*
X928600D03*
X926400D03*
X912900Y216500D03*
X910700D03*
X928600Y228327D03*
X926400D03*
X926700Y212600D03*
X924500D03*
X934800D03*
X932600D03*
X955200Y137800D03*
X953000D03*
X951000Y149600D03*
X948800D03*
X954368Y161468D03*
X952168D03*
X954368Y157468D03*
X952168D03*
X966200Y165338D03*
X964000D03*
X974000D03*
X971800D03*
X958300Y173218D03*
X956100D03*
X966200D03*
X964000D03*
X974000D03*
X971800D03*
X958300Y165338D03*
X956100D03*
X950300D03*
X948100D03*
X950300Y173218D03*
X948100D03*
X973900Y177150D03*
X966200Y185168D03*
X964000D03*
X974000D03*
X971800D03*
X958300Y192900D03*
X956100D03*
X966200D03*
X964000D03*
X974000D03*
X971800D03*
X942700Y204700D03*
X973850Y216510D03*
X941700Y224400D03*
Y232300D03*
X960100Y224400D03*
X957900D03*
X952300D03*
X950100D03*
X968000D03*
X965800D03*
X952300Y232300D03*
X950100D03*
X960100D03*
X957900D03*
X968000D03*
X965800D03*
X995600Y161400D03*
X993400D03*
X995600Y169268D03*
X993400D03*
X995600Y173268D03*
X993400D03*
X995500Y157500D03*
X993300D03*
X991600Y165400D03*
X989400D03*
X995600Y177168D03*
X993400D03*
X995600Y181068D03*
X993400D03*
X990600Y185500D03*
X988400D03*
X995600Y188968D03*
X993400D03*
X995600Y192868D03*
X993400D03*
X995600Y196868D03*
X993400D03*
X976100Y177150D03*
X995600Y208668D03*
X993400D03*
X995600Y200768D03*
X993400D03*
X995600Y204668D03*
X993400D03*
X995600Y224368D03*
X993400D03*
X976050Y216510D03*
X995600Y228368D03*
X993400D03*
X995600Y212568D03*
X993400D03*
X995600Y216518D03*
X993400D03*
X995600Y220468D03*
X993400D03*
X995600Y236200D03*
X993400D03*
X995600Y232268D03*
X993400D03*
G54D52*
X476614Y167493D03*
Y162493D03*
Y157493D03*
G54D34*
X134251Y153543D03*
X161811D03*
X151968D03*
X144094D03*
G54D25*
X67400Y269300D03*
X72100D03*
X228500Y156200D03*
X276200Y154100D03*
G54D71*
G01X1015079Y23435D02*
Y20534D01*
X1014311Y19766D01*
X1010973D01*
X1010229Y19022D01*
G01X1015079Y31110D02*
X1013068D01*
X1010975Y29017D01*
G01X1307662Y700219D02*
Y693912D01*
X1307400Y693650D01*
G54D26*
X67400Y274900D03*
X72100D03*
X228500Y161800D03*
X276200Y159700D03*
G54D53*
X473231Y235560D03*
Y274930D03*
X487404Y255245D03*
G54D44*
X193900Y274372D03*
X183900D03*
X213900D03*
X203900D03*
X302500Y207200D03*
X292500D03*
X326200D03*
X336200D03*
X312500D03*
X346200D03*
X465485Y200680D03*
Y190680D03*
Y180680D03*
X488462Y180761D03*
Y190761D03*
Y200761D03*
X501742Y215594D03*
X511742D03*
X521742D03*
X531742D03*
X772300Y16200D03*
X762300D03*
X752300D03*
X785300Y16100D03*
X795300D03*
X805300D03*
X819291Y265354D03*
Y285354D03*
X1075197Y92126D03*
Y112126D03*
X1348785Y161642D03*
X1323195D03*
X1348785Y179358D03*
X1323195D03*
G54D62*
X900668Y161468D03*
X902868D03*
X905000Y165300D03*
X907200D03*
X899000Y169268D03*
X901200D03*
X899000Y173218D03*
X901200D03*
X899000Y196818D03*
X901200D03*
X899000Y208668D03*
X901200D03*
X899000Y200768D03*
X901200D03*
X899000Y204718D03*
X901200D03*
X899000Y192918D03*
X901200D03*
X899000Y188968D03*
X901200D03*
X904100Y185200D03*
X906300D03*
X899000Y181068D03*
X901200D03*
X899000Y177168D03*
X901200D03*
X899000Y236200D03*
X901200D03*
X899000Y212568D03*
X901200D03*
X899000Y216518D03*
X901200D03*
X899000Y220468D03*
X901200D03*
X899000Y224368D03*
X901200D03*
X899000Y228318D03*
X901200D03*
X899000Y232268D03*
X901200D03*
X938200Y141700D03*
X940400D03*
X930250Y157500D03*
X932450D03*
X938350D03*
X940550D03*
X932600Y165338D03*
X934800D03*
X940500D03*
X924500Y173218D03*
X926700D03*
X932600D03*
X934800D03*
X940500D03*
X932600Y185168D03*
X934800D03*
X940500D03*
X924500Y192900D03*
X926700D03*
X940500D03*
X932600D03*
X934800D03*
X918300Y216550D03*
X920500D03*
X934400Y232300D03*
X936600D03*
X926400D03*
X928600D03*
X934400Y224400D03*
X936600D03*
X926400D03*
X928600D03*
X940500Y212600D03*
X957400Y126000D03*
X959600D03*
X964050Y161400D03*
X966250D03*
X970900Y149600D03*
X973100D03*
X942700Y165338D03*
Y173218D03*
X956100Y185168D03*
X958300D03*
X948100Y204700D03*
X950300D03*
X948100Y185168D03*
X950300D03*
X956100Y204700D03*
X958300D03*
X964000D03*
X966200D03*
X971800D03*
X974000D03*
X942700Y185168D03*
Y192900D03*
X948100D03*
X950300D03*
X950100Y236210D03*
X952300D03*
X965700Y220500D03*
X967900D03*
X957900Y228327D03*
X960100D03*
X957800Y220500D03*
X960000D03*
X957900Y236210D03*
X960100D03*
X965800Y236200D03*
X968000D03*
X950100Y220500D03*
X952300D03*
X965800Y228300D03*
X968000D03*
X950100Y228327D03*
X952300D03*
X948100Y212600D03*
X950300D03*
X956100D03*
X958300D03*
X964000D03*
X966200D03*
X971600Y212624D03*
X973800D03*
X942700Y212600D03*
X997300Y137768D03*
X999500D03*
X997300Y129900D03*
X999500D03*
X997300Y141768D03*
X999500D03*
X982500Y137800D03*
X984700D03*
X997300Y145668D03*
X999500D03*
X997300Y149618D03*
X999500D03*
X997300Y153600D03*
X999500D03*
X999168Y161468D03*
X1001368D03*
X981500Y177150D03*
X983700D03*
X981350Y185050D03*
X983550D03*
X1001100Y236200D03*
X1003300D03*
X981400Y216505D03*
X983600D03*
G54D17*
G01X1278494Y149375D02*
X1284276D01*
X1306890Y171989D01*
Y176681D01*
X1316968Y186759D01*
X1326682D01*
X1331243Y182198D01*
X4100Y865800D03*
X46678Y-681D03*
X50400Y826100D03*
X107400Y119000D03*
X1374900Y761800D03*
X1383700Y138500D03*
X1396600Y862800D03*
G54D35*
X113300Y276600D03*
X131700Y275700D03*
X113000Y280500D03*
X113100Y284100D03*
X125100Y282500D03*
X131700Y280000D03*
X294000Y716000D03*
X300500Y715613D03*
X528100Y767300D03*
G54D72*
G01X105851Y637000D02*
Y611436D01*
G01X136651Y653036D02*
X133157Y649542D01*
X108752D01*
X105851Y646641D01*
Y637000D01*
G01X323406Y771148D02*
X319406D01*
G01D02*
X318710D01*
X317561Y769999D01*
X308243D01*
X306094Y772148D01*
X303406D01*
G01X867940Y37350D02*
Y34560D01*
X869500Y33000D01*
Y31077D01*
X869447Y31024D01*
G01X851782Y779219D02*
X852619D01*
X855150Y776688D01*
Y776682D01*
X855500Y776332D01*
Y775500D01*
G54D36*
X105500Y287800D03*
X103500Y457800D03*
X113000Y458800D03*
X197800Y443800D03*
X189600Y443700D03*
X193600D03*
X185500Y457800D03*
X197700Y454635D03*
X177500Y457800D03*
X184500Y545300D03*
X232600Y98600D03*
X210086Y201400D03*
X206076D03*
X202638Y434145D03*
X220838Y431945D03*
X201800Y443800D03*
X230572Y458913D03*
X201700Y454635D03*
X210300Y454100D03*
X214300D03*
X225000Y534800D03*
Y518300D03*
X249995Y98758D03*
X236800Y98500D03*
X251000Y498200D03*
X263000Y752300D03*
X290500Y145800D03*
X285000Y748800D03*
X267500D03*
X295678Y732731D03*
X278050Y733317D03*
X298554Y719713D03*
X286406Y719698D03*
X282406D03*
X290500Y719800D03*
X294506Y719698D03*
X293678Y756731D03*
X289678D03*
X279500Y756300D03*
X282378Y768731D03*
X301000Y744300D03*
X317000Y744800D03*
X311678Y732731D03*
X327678D03*
X310406Y719698D03*
X302554Y719713D03*
X311178Y756731D03*
X307178D03*
X325678D03*
X321678D03*
X495906Y771698D03*
X499906D03*
X498000Y800800D03*
X480800D03*
X502678Y808731D03*
X492500Y808300D03*
X482000D03*
X491900Y784700D03*
X495878Y820731D03*
X521820Y130370D03*
X513820D03*
X525820D03*
X517820D03*
X527000Y771500D03*
X521900Y771400D03*
X517800Y771500D03*
X513700D03*
X509600D03*
X514000Y795800D03*
X530000D03*
X506678Y808731D03*
X520178D03*
X524678Y784731D03*
X534678Y808731D03*
X524178D03*
X570345Y130330D03*
X538678Y808731D03*
X540678Y784731D03*
X542800Y809100D03*
X578467Y130330D03*
X582467D03*
X574345D03*
X584363Y220908D03*
X592363D03*
X588363D03*
X620048Y130544D03*
X612026Y130552D03*
X624048Y130544D03*
X616026Y130552D03*
X659500Y130300D03*
X650500D03*
X655000D03*
X646000D03*
X641963Y234908D03*
X720100Y38100D03*
X715390Y29680D03*
X715130Y53200D03*
X834252Y14300D03*
X820212Y14219D03*
X830252Y14300D03*
X826138Y13604D03*
X838252Y14300D03*
X846252D03*
X873100Y27300D03*
X842252Y14300D03*
X864906Y748698D03*
X868906D03*
X857500Y778300D03*
X841000Y774800D03*
X852400Y762200D03*
X870400Y785700D03*
X844810Y785890D03*
X865378Y797731D03*
X877300Y27300D03*
X906500Y78800D03*
X902000D03*
X897500D03*
X893000D03*
X888500D03*
X875000D03*
X884000D03*
X879500D03*
X893406Y748698D03*
X889306D03*
X885306D03*
X881306D03*
X877200Y748600D03*
X887500Y781300D03*
X882203Y762295D03*
X878600Y785300D03*
X896178Y785731D03*
X892178D03*
X911000Y78800D03*
X915500D03*
X920000D03*
X933500D03*
X929000D03*
X924500D03*
X938000D03*
X951500D03*
Y89800D03*
X947000Y78800D03*
Y89800D03*
X942500Y78800D03*
Y89800D03*
X956000Y78800D03*
X994700Y101100D03*
X1069700Y4600D03*
X1044161Y17868D03*
X1068750Y24550D03*
X1073250Y36550D03*
X1065475Y40873D03*
X1061342Y64994D03*
X1310128Y677167D03*
X1302000Y703300D03*
X1298000Y707300D03*
X1312900Y690200D03*
X1310900Y713700D03*
X1310100Y726200D03*
X1338128Y677167D03*
X1330128D03*
X1326128D03*
X1322128D03*
X1314128D03*
X1319500Y705800D03*
X1336000Y701800D03*
X1329900Y714200D03*
X1325900D03*
X1330400Y690200D03*
X1344900Y714200D03*
X1340900D03*
X1346900Y690200D03*
G54D27*
X92200Y273940D03*
X95959Y513567D03*
X82017Y490086D03*
Y494086D03*
X84200Y510500D03*
Y502500D03*
X95387Y496084D03*
Y500084D03*
X84200Y506500D03*
X95387Y504084D03*
X84200Y514500D03*
X95820Y541681D03*
X96736Y526266D03*
X95959Y517567D03*
X84200Y518500D03*
X95820Y545681D03*
X70700Y535000D03*
X84200Y538500D03*
Y534500D03*
X70300Y526900D03*
X74200Y522500D03*
X96736Y530266D03*
X74000Y545700D03*
X84200Y554500D03*
X95820Y549681D03*
X84162Y558640D03*
X101900Y275460D03*
X130592Y470680D03*
X135109Y426337D03*
X135108Y430365D03*
X181700Y517500D03*
X214338Y441845D03*
X211238Y425445D03*
X217800Y448200D03*
X204600Y502800D03*
Y506800D03*
Y510900D03*
Y514900D03*
X213200Y542500D03*
Y538500D03*
Y546500D03*
Y550500D03*
X254200Y477500D03*
X243600Y455600D03*
Y473600D03*
X234843Y477829D03*
Y473829D03*
X254200Y481500D03*
X253200Y486000D03*
Y490000D03*
X234843Y485929D03*
Y489929D03*
X234800Y506000D03*
Y502000D03*
X718750Y17920D03*
X870100Y765800D03*
X858640Y790220D03*
X905600Y112500D03*
X900000Y765400D03*
X1007628Y23605D03*
Y27605D03*
X1037681Y2842D03*
X1045263Y2948D03*
X1052112Y18357D03*
X1073200Y36500D03*
X1068700Y24500D03*
X1073200Y32500D03*
X1068700Y20500D03*
X1054900Y36615D03*
X1065425Y48823D03*
Y44323D03*
X1061346Y68390D03*
Y72400D03*
X1077500Y3500D03*
X1077600Y12400D03*
X1077500Y7600D03*
X1378239Y169235D03*
G54D45*
X195000Y409040D03*
Y411600D03*
X187600Y409040D03*
Y411600D03*
X195000Y414160D03*
X187600D03*
X207938Y436405D03*
Y433845D03*
Y431285D03*
X215338Y436405D03*
Y433845D03*
Y431285D03*
G54D54*
X514309Y-315D03*
Y52087D03*
X530057Y106457D03*
X557616Y-315D03*
Y52087D03*
X547773Y106457D03*
X600923Y-315D03*
Y52087D03*
X591080Y106457D03*
X573364D03*
X634388D03*
X616671D03*
X644230Y-315D03*
Y52087D03*
X659978Y106457D03*
X687537Y-315D03*
Y52087D03*
X677695Y106457D03*
X1116671Y-315D03*
Y52087D03*
X1132419Y106457D03*
X1159978Y-315D03*
Y52087D03*
X1175726Y106457D03*
X1150135D03*
X1203285Y-315D03*
Y52087D03*
X1193442Y106457D03*
X1246592Y-315D03*
Y52087D03*
X1236750Y106457D03*
X1219033D03*
X1280057D03*
X1262340D03*
X1289899Y-315D03*
Y52087D03*
G54D18*
X41603Y177598D03*
X65579D03*
X57587D03*
X49595D03*
X45559Y187598D03*
X37567D03*
X53551D03*
X73571Y177598D03*
X81563D03*
X77607Y187598D03*
X69615D03*
X85599D03*
G54D63*
X943111Y5908D03*
X935236D03*
X927361D03*
X919486D03*
X911616D03*
X943111Y13778D03*
X935236D03*
X927361D03*
X919486D03*
X911616D03*
X958856Y5908D03*
X950986D03*
X958856Y13778D03*
X950986D03*
G54D73*
G01X178250Y517500D02*
X177735D01*
X175216Y520019D01*
G01X295560Y749750D02*
X296995D01*
X298500Y751255D01*
Y752000D01*
G01X290440Y743250D02*
Y736802D01*
X289819Y736181D01*
G01X273500Y736150D02*
X273162Y736488D01*
Y743219D01*
G01X322440Y743250D02*
Y736443D01*
X322178Y736181D01*
G01X306440Y743250D02*
Y736443D01*
X306178Y736181D01*
G01X311560Y749750D02*
Y752860D01*
X312556Y753856D01*
X313452D01*
G01X327560Y749750D02*
Y753060D01*
X328500Y754000D01*
X330000D01*
G01X491782Y801719D02*
X493363D01*
X494582Y800500D01*
G01X503440Y795250D02*
Y788443D01*
X503178Y788181D01*
G01X487000Y788150D02*
X486662Y788488D01*
Y795219D01*
G01X524560Y801750D02*
Y804286D01*
X526274Y806000D01*
G01X508560Y801750D02*
X510250D01*
X511500Y803000D01*
G01X535440Y795250D02*
Y788443D01*
X535178Y788181D01*
G01X519440Y795250D02*
Y789088D01*
X519069Y788717D01*
G01X540560Y801750D02*
Y804060D01*
X542500Y806000D01*
G01X871550Y52700D02*
Y49500D01*
X873060Y47990D01*
Y43850D01*
G01X857550Y778250D02*
X859661Y776139D01*
Y773929D01*
X861340Y772250D01*
X862940D01*
G01X876940D02*
X874250D01*
X874000Y772000D01*
G01X841500Y771000D02*
X841000Y771500D01*
Y774750D01*
G01D02*
X844631D01*
X846662Y772719D01*
G01X847500Y765650D02*
X846662Y766488D01*
Y772719D01*
G01X862940Y772250D02*
Y765943D01*
X862678Y765681D01*
G01X1341662Y700719D02*
Y693912D01*
X1341400Y693650D01*
G01X1376734Y182245D02*
X1378674Y184185D01*
X1382028D01*
X1382138Y184295D01*
Y184129D01*
G54D28*
X88800Y273940D03*
X92559Y513567D03*
X78617Y490086D03*
Y494086D03*
X80800Y510500D03*
Y502500D03*
X91987Y496084D03*
Y500084D03*
X80800Y506500D03*
X91987Y504084D03*
X80800Y514500D03*
X92420Y541681D03*
X93336Y526266D03*
X92559Y517567D03*
X80800Y518500D03*
X92420Y545681D03*
X67300Y535000D03*
X80800Y538500D03*
Y534500D03*
X66900Y526900D03*
X70800Y522500D03*
X93336Y530266D03*
X70600Y545700D03*
X80800Y554500D03*
X92420Y549681D03*
X80762Y558640D03*
X98500Y275460D03*
X131709Y426337D03*
X131708Y430365D03*
X127192Y470680D03*
X178300Y517500D03*
X210938Y441845D03*
X207838Y425445D03*
X231443Y477829D03*
X214400Y448200D03*
X231443Y473829D03*
X201200Y502800D03*
Y506800D03*
X231443Y485929D03*
Y489929D03*
X231400Y506000D03*
Y502000D03*
X201200Y510900D03*
Y514900D03*
X209800Y542500D03*
Y538500D03*
Y546500D03*
Y550500D03*
X250800Y477500D03*
X240200Y455600D03*
Y473600D03*
X250800Y481500D03*
X249800Y486000D03*
Y490000D03*
X715350Y17920D03*
X866700Y765800D03*
X855240Y790220D03*
X902200Y112500D03*
X896600Y765400D03*
X1004228Y23605D03*
Y27605D03*
X1041863Y2948D03*
X1034281Y2842D03*
X1074100Y3500D03*
X1074200Y12400D03*
X1074100Y7600D03*
X1048712Y18357D03*
X1069800Y36500D03*
X1065300Y24500D03*
X1069800Y32500D03*
X1065300Y20500D03*
X1051500Y36615D03*
X1062025Y48823D03*
Y44323D03*
X1057946Y68390D03*
Y72400D03*
X1374839Y169235D03*
G54D19*
X54378Y237402D03*
G54D46*
X240840Y460900D03*
X243400D03*
X245960D03*
X240840Y468300D03*
X243400D03*
X245960D03*
G54D55*
X535962Y37484D03*
X579269D03*
X622577D03*
X665884D03*
X1138324D03*
X1181631D03*
X1224939D03*
X1268246D03*
G54D64*
X907900Y127000D03*
Y124800D03*
X915793Y127000D03*
Y124800D03*
X923600Y127000D03*
Y124800D03*
X931532Y127000D03*
Y124800D03*
X915768Y180068D03*
Y177868D03*
X915730Y237800D03*
Y235600D03*
X919700Y237800D03*
Y235600D03*
X907893Y237800D03*
Y235600D03*
X911800Y237800D03*
Y235600D03*
X923604Y237900D03*
Y235700D03*
X966900Y127100D03*
Y124900D03*
X974768Y127100D03*
Y124900D03*
X970845Y237600D03*
Y235400D03*
X974800Y237600D03*
Y235400D03*
X982728Y127100D03*
Y124900D03*
X978760Y237600D03*
Y235400D03*
X982697Y237600D03*
Y235400D03*
X986600Y237600D03*
Y235400D03*
G54D37*
X105500Y291200D03*
X103500Y461200D03*
X113000Y462200D03*
X185500Y461200D03*
X197800Y447200D03*
X189600Y447100D03*
X193600D03*
X197700Y458035D03*
X177500Y461200D03*
X184500Y548700D03*
X232600Y102000D03*
X210086Y204800D03*
X206076D03*
X202638Y437545D03*
X220838Y435345D03*
X230572Y462313D03*
X201800Y447200D03*
X201700Y458035D03*
X210300Y457500D03*
X214300D03*
X225000Y538200D03*
Y521700D03*
X249995Y102158D03*
X236800Y101900D03*
X251000Y501600D03*
X263000Y755700D03*
X290500Y149200D03*
X295678Y736131D03*
X278050Y736717D03*
X298554Y723113D03*
X286406Y723098D03*
X282406D03*
X290500Y723200D03*
X294506Y723098D03*
X285000Y752200D03*
X267500D03*
X293678Y760131D03*
X289678D03*
X279500Y759700D03*
X282378Y772131D03*
X301000Y747700D03*
X317000Y748200D03*
X311678Y736131D03*
X327678D03*
X310406Y723098D03*
X302554Y723113D03*
X311178Y760131D03*
X307178D03*
X325678D03*
X321678D03*
X495906Y775098D03*
X499906D03*
X498000Y804200D03*
X480800D03*
X502678Y812131D03*
X492500Y811700D03*
X482000D03*
X491900Y788100D03*
X495878Y824131D03*
X521820Y133770D03*
X513820D03*
X525820D03*
X517820D03*
X527000Y774900D03*
X521900Y774800D03*
X517800Y774900D03*
X513700D03*
X509600D03*
X514000Y799200D03*
X530000D03*
X506678Y812131D03*
X520178D03*
X524678Y788131D03*
X534678Y812131D03*
X524178D03*
X570345Y133730D03*
X538678Y812131D03*
X540678Y788131D03*
X542800Y812500D03*
X578467Y133730D03*
X582467D03*
X574345D03*
X584363Y224308D03*
X592363D03*
X588363D03*
X620048Y133944D03*
X612026Y133952D03*
X624048Y133944D03*
X616026Y133952D03*
X659500Y133700D03*
X650500D03*
X655000D03*
X646000D03*
X641963Y238308D03*
X715390Y33080D03*
X720100Y41500D03*
X715130Y56600D03*
X834252Y17700D03*
X820212Y17619D03*
X830252Y17700D03*
X826138Y17004D03*
X838252Y17700D03*
X846252D03*
X873100Y30700D03*
X842252Y17700D03*
X857500Y781700D03*
X841000Y778200D03*
X852400Y765600D03*
X864906Y752098D03*
X868906D03*
X870400Y789100D03*
X844810Y789290D03*
X865378Y801131D03*
X877300Y30700D03*
X906500Y82200D03*
X902000D03*
X897500D03*
X893000D03*
X888500D03*
X875000D03*
X884000D03*
X879500D03*
X882203Y765695D03*
X893406Y752098D03*
X889306D03*
X885306D03*
X881306D03*
X877200Y752000D03*
X887500Y784700D03*
X878600Y788700D03*
X896178Y789131D03*
X892178D03*
X911000Y82200D03*
X915500D03*
X920000D03*
X933500D03*
X929000D03*
X924500D03*
X938000D03*
X951500D03*
Y93200D03*
X947000Y82200D03*
Y93200D03*
X942500Y82200D03*
Y93200D03*
X956000Y82200D03*
X994700Y104500D03*
X1069700Y8000D03*
X1044161Y21268D03*
X1068750Y27950D03*
X1073250Y39950D03*
X1061342Y68394D03*
X1065475Y44273D03*
X1310128Y680567D03*
X1302000Y706700D03*
X1298000Y710700D03*
X1312900Y693600D03*
X1310900Y717100D03*
X1310100Y729600D03*
X1338128Y680567D03*
X1330128D03*
X1326128D03*
X1322128D03*
X1314128D03*
X1319500Y709200D03*
X1336000Y705200D03*
X1330400Y693600D03*
X1329900Y717600D03*
X1325900D03*
X1344900D03*
X1340900D03*
X1346900Y693600D03*
G54D74*
G01X113795Y504049D02*
X113865Y504119D01*
Y504951D01*
X115114Y506200D01*
X124650D01*
X125365Y505485D01*
Y504814D01*
X124822Y504271D01*
G01X111937Y504985D02*
X112008Y505056D01*
X112838D01*
X114782Y507000D01*
X124982D01*
X127710Y504272D01*
X127973D01*
G01X184615Y475812D02*
X184515D01*
X183928Y476399D01*
X178633D01*
X173717Y481315D01*
Y483876D01*
X175215Y485374D01*
G01X175217Y482225D02*
Y480947D01*
X178965Y477199D01*
X184027D01*
X184615Y477787D01*
G01X191479Y476755D02*
X191409Y476825D01*
Y477655D01*
X188372Y480692D01*
X180059D01*
X178106Y482645D01*
Y483511D01*
X176865Y484752D01*
Y486874D01*
X175216Y488523D01*
G01X178365Y485374D02*
X178906Y484833D01*
Y482977D01*
X180391Y481492D01*
X188704D01*
X191974Y478222D01*
X192806D01*
X192876Y478152D01*
G01X878907Y176300D02*
X879007D01*
X879207Y176500D01*
X880539D01*
X884760Y180721D01*
X891200D01*
G02X891501Y180596I-1J-426D01*
G01X891998Y180099D01*
G02X891645Y179133I-401J-401D01*
G01X891353Y179134D01*
G03X891349I-2J-599D01*
G01X890158D01*
G01X894095D02*
X892067Y181162D01*
G03X891200Y181521I-867J-867D01*
G01X884428D01*
X880207Y177300D01*
X879207D01*
X879007Y177500D01*
X878907D01*
G01X929528Y139764D02*
X927141Y137377D01*
X924948D01*
X924004Y136433D01*
Y130915D01*
X922592Y129503D01*
X921011D01*
X920104Y128596D01*
Y116426D01*
X920066Y116388D01*
G01X929528Y151575D02*
X927250Y149297D01*
Y147104D01*
X925546Y145400D01*
X925097D01*
X923204Y143507D01*
Y131247D01*
X922260Y130303D01*
X920679D01*
X919304Y128928D01*
Y117642D01*
X918981Y117319D01*
G01X905180Y109071D02*
X909580Y113471D01*
Y116770D01*
X911393Y118583D01*
Y133440D01*
X913780Y135827D01*
G01X894850Y112060D02*
X895800Y113010D01*
Y120040D01*
X897830Y122070D01*
X902850D01*
X903519Y122739D01*
Y132533D01*
X901969Y134083D01*
Y135827D01*
G01X898000Y117000D02*
Y117208D01*
X899000Y118208D01*
X902291D01*
X904356Y120273D01*
Y128596D01*
X905263Y129503D01*
X906783D01*
X907550Y130270D01*
Y137682D01*
X909632Y139764D01*
X909843D01*
G01X937402Y155512D02*
X935815Y153925D01*
Y142726D01*
X934403Y141314D01*
X932822D01*
X931915Y140407D01*
Y134815D01*
X930540Y133440D01*
X928885D01*
X927978Y132533D01*
Y122689D01*
X929000Y121667D01*
G01X938000Y125604D02*
X938989Y126593D01*
Y128928D01*
X940364Y130303D01*
X942000D01*
X942889Y131192D01*
Y141089D01*
X944700Y142900D01*
Y147773D01*
X944157Y148316D01*
X943084D01*
X941400Y150000D01*
X940721D01*
X939789Y150932D01*
Y153962D01*
X941339Y155512D01*
G01X933465Y151575D02*
X935015Y150025D01*
Y143058D01*
X934108Y142151D01*
X932527D01*
X931115Y140739D01*
Y135147D01*
X930208Y134240D01*
X928553D01*
X927178Y132865D01*
Y119000D01*
G01X941339Y151575D02*
X943609Y149305D01*
X944300D01*
X945500Y148105D01*
Y142568D01*
X943689Y140757D01*
Y130860D01*
X942332Y129503D01*
X940696D01*
X939789Y128596D01*
Y121900D01*
G01X912200Y112300D02*
Y124334D01*
X912230Y124364D01*
Y128596D01*
X913274Y129640D01*
X918884D01*
X920347Y131103D01*
X920867D01*
X921654Y131890D01*
G01X915790Y161420D02*
X915800Y161410D01*
Y157429D01*
X917717Y155512D01*
G01X956200Y114274D02*
X955536Y114938D01*
Y130340D01*
X957086Y131890D01*
G01X954736Y114500D02*
Y133477D01*
X957086Y135827D01*
G01X968553Y114629D02*
Y114729D01*
X969140Y115316D01*
Y117726D01*
X970447Y119033D01*
Y133440D01*
X972834Y135827D01*
G01X964960Y155512D02*
Y153914D01*
X962573Y151527D01*
Y118566D01*
X961740Y117733D01*
Y115744D01*
X961153Y115157D01*
Y115057D01*
G01X970528Y114629D02*
Y114729D01*
X969940Y115317D01*
Y117394D01*
X971247Y118701D01*
Y130303D01*
X972834Y131890D01*
G01X964960Y151575D02*
X963753D01*
X963373Y151195D01*
Y118234D01*
X962540Y117401D01*
Y115745D01*
X963128Y115157D01*
Y115057D01*
G01X996875Y117459D02*
X996805Y117529D01*
X995973D01*
X994890Y118612D01*
Y140718D01*
X993494Y142114D01*
X991544D01*
X989194Y139764D01*
X988582D01*
G01X986105Y116251D02*
Y116351D01*
X985517Y116939D01*
Y117626D01*
X986995Y119104D01*
Y141095D01*
X988051Y142151D01*
X989225D01*
X991300Y144226D01*
Y145800D01*
G01X995478Y116062D02*
X995408Y116132D01*
Y116962D01*
X994090Y118280D01*
Y140386D01*
X993162Y141314D01*
X991876D01*
X990800Y140238D01*
Y138045D01*
X988582Y135827D01*
G01X980708Y143701D02*
X979121Y142114D01*
Y119104D01*
X978776Y118759D01*
Y113500D01*
X979364Y112912D01*
Y112812D01*
G01X980708Y147638D02*
Y146008D01*
X978321Y143621D01*
Y119436D01*
X977976Y119091D01*
Y113499D01*
X977389Y112912D01*
Y112812D01*
G01X992519Y139764D02*
X992700Y139583D01*
Y130327D01*
X990969Y128596D01*
Y114663D01*
X991332Y114300D01*
G01X984130Y116251D02*
Y116351D01*
X984717Y116938D01*
Y117958D01*
X986195Y119436D01*
Y130340D01*
X984645Y131890D01*
G01Y151575D02*
X986995Y149225D01*
X989189D01*
X991300Y147114D01*
Y145800D01*
G54D65*
X927600Y142700D03*
Y144900D03*
X939400Y144500D03*
Y146700D03*
X931500Y144600D03*
Y146800D03*
X951200Y144800D03*
Y147000D03*
X943400Y144700D03*
Y146900D03*
X946400Y159200D03*
Y161400D03*
G54D47*
X280300Y148900D03*
X301700Y780100D03*
X573634Y243270D03*
X621263Y233108D03*
X695200Y817300D03*
X716287Y201942D03*
X1162807Y823010D03*
X1306700Y271400D03*
X1323900Y817400D03*
G54D29*
X93300Y476400D03*
Y472400D03*
X80642Y463549D03*
X77500Y478600D03*
X93300Y484600D03*
Y480400D03*
X70800Y498500D03*
X70408Y506552D03*
X80800Y546500D03*
Y530500D03*
Y542500D03*
Y522500D03*
Y550500D03*
X80622Y562789D03*
X76700Y729300D03*
Y733300D03*
X114400Y288100D03*
X108400Y731900D03*
Y727900D03*
X139146Y430391D03*
X189500Y403300D03*
X189700Y419800D03*
X210802Y479619D03*
Y475619D03*
X206826Y448165D03*
X222838Y466300D03*
Y462300D03*
X211023Y487704D03*
Y483704D03*
X210050Y495744D03*
Y491744D03*
X209800Y525500D03*
Y521500D03*
Y534500D03*
Y530500D03*
X222800Y550500D03*
Y558500D03*
Y554500D03*
X239800Y478000D03*
X261838Y477600D03*
X249800Y494100D03*
X239800Y490000D03*
Y486000D03*
Y482000D03*
X261838Y481600D03*
X260300Y588500D03*
Y593000D03*
X294300Y578500D03*
Y583000D03*
Y588500D03*
X507000Y788700D03*
X712163Y37236D03*
X715370Y29700D03*
X715390Y25490D03*
X715130Y53200D03*
Y49100D03*
X862860Y788880D03*
X878510Y792910D03*
X952800Y67900D03*
Y72000D03*
X1017146Y57597D03*
X1043500Y36615D03*
G54D56*
X533010Y69803D03*
X530057Y67048D03*
X535962Y64292D03*
X524151Y69803D03*
X527104Y64292D03*
X535962Y49331D03*
X527104D03*
X530057Y52087D03*
X533010Y54843D03*
X524151D03*
X533010Y99725D03*
X530057Y96969D03*
X535962Y94213D03*
X524151Y99725D03*
X527104Y94213D03*
X533010Y84764D03*
X530057Y82008D03*
X535962Y79252D03*
X524151Y84764D03*
X527104Y79252D03*
X567458Y54843D03*
X570411Y49331D03*
Y64292D03*
X567458Y69803D03*
X541868D03*
X538915Y67048D03*
X547773D03*
X544821Y64292D03*
Y49331D03*
X547773Y52087D03*
X538915D03*
X541868Y54843D03*
X570411Y79252D03*
Y94213D03*
X567458Y84764D03*
Y99725D03*
X541868D03*
X538915Y96969D03*
X547773D03*
X544821Y94213D03*
X541868Y84764D03*
X538915Y82008D03*
X547773D03*
X544821Y79252D03*
X576317Y54843D03*
X585175D03*
X573364Y52087D03*
X582222D03*
X591080D03*
X579269Y49331D03*
X588128D03*
X576317Y69803D03*
X585175D03*
X573364Y67048D03*
X582222D03*
X591080D03*
X579269Y64292D03*
X588128D03*
X579269Y79252D03*
X588128D03*
X582222Y82008D03*
X591080D03*
X585175Y84764D03*
X576317D03*
X573364Y82008D03*
X576317Y99725D03*
X585175D03*
X573364Y96969D03*
X582222D03*
X579269Y94213D03*
X588128D03*
X591080Y96969D03*
X619624Y54843D03*
X628482D03*
X616671Y52087D03*
X625529D03*
X634388D03*
X622577Y49331D03*
X631435D03*
X619624Y69803D03*
X628482D03*
X616671Y67048D03*
X625529D03*
X634388D03*
X622577Y64292D03*
X631435D03*
X610766Y54843D03*
X613718Y49331D03*
Y64292D03*
X610766Y69803D03*
X622577Y79252D03*
X631435D03*
X625529Y82008D03*
X634388D03*
X628482Y84764D03*
X619624D03*
X616671Y82008D03*
X619624Y99725D03*
X628482D03*
X616671Y96969D03*
X625529D03*
X622577Y94213D03*
X631435D03*
X634388Y96969D03*
X613718Y79252D03*
Y94213D03*
X610766Y84764D03*
Y99725D03*
X662931Y54843D03*
X671789D03*
X659978Y52087D03*
X668836D03*
X665884Y49331D03*
X662931Y69803D03*
X671789D03*
X659978Y67048D03*
X668836D03*
X665884Y64292D03*
X654073Y54843D03*
X657025Y49331D03*
Y64292D03*
X654073Y69803D03*
X665884Y79252D03*
X668836Y82008D03*
X671789Y84764D03*
X662931D03*
X659978Y82008D03*
X662931Y99725D03*
X671789D03*
X659978Y96969D03*
X668836D03*
X665884Y94213D03*
X657025Y79252D03*
Y94213D03*
X654073Y84764D03*
Y99725D03*
X677695Y52087D03*
X674742Y49331D03*
X677695Y67048D03*
X674742Y64292D03*
Y79252D03*
X677695Y82008D03*
X674742Y94213D03*
X677695Y96969D03*
X1135372Y69803D03*
X1144230D03*
X1132419Y67048D03*
X1141277D03*
X1138324Y64292D03*
X1126513Y69803D03*
X1129466Y64292D03*
X1138324Y49331D03*
X1129466D03*
X1141277Y52087D03*
X1132419D03*
X1144230Y54843D03*
X1135372D03*
X1126513D03*
X1135372Y99725D03*
X1144230D03*
X1132419Y96969D03*
X1141277D03*
X1138324Y94213D03*
X1126513Y99725D03*
X1129466Y94213D03*
X1135372Y84764D03*
X1144230D03*
X1132419Y82008D03*
X1141277D03*
X1138324Y79252D03*
X1126513Y84764D03*
X1129466Y79252D03*
X1178679Y54843D03*
X1175726Y52087D03*
X1178679Y69803D03*
X1175726Y67048D03*
X1169820Y54843D03*
X1172773Y49331D03*
Y64292D03*
X1169820Y69803D03*
X1150135Y67048D03*
X1147183Y64292D03*
Y49331D03*
X1150135Y52087D03*
X1178679Y84764D03*
X1175726Y82008D03*
X1178679Y99725D03*
X1175726Y96969D03*
X1172773Y79252D03*
Y94213D03*
X1169820Y84764D03*
Y99725D03*
X1150135Y96969D03*
X1147183Y94213D03*
X1150135Y82008D03*
X1147183Y79252D03*
X1187537Y54843D03*
X1184584Y52087D03*
X1193442D03*
X1181631Y49331D03*
X1190490D03*
X1187537Y69803D03*
X1184584Y67048D03*
X1193442D03*
X1181631Y64292D03*
X1190490D03*
X1181631Y79252D03*
X1190490D03*
X1184584Y82008D03*
X1193442D03*
X1187537Y84764D03*
Y99725D03*
X1184584Y96969D03*
X1181631Y94213D03*
X1190490D03*
X1193442Y96969D03*
X1221986Y54843D03*
X1230844D03*
X1219033Y52087D03*
X1227891D03*
X1236750D03*
X1224939Y49331D03*
X1233797D03*
X1221986Y69803D03*
X1230844D03*
X1219033Y67048D03*
X1227891D03*
X1236750D03*
X1224939Y64292D03*
X1233797D03*
X1213128Y54843D03*
X1216080Y49331D03*
Y64292D03*
X1213128Y69803D03*
X1224939Y79252D03*
X1233797D03*
X1227891Y82008D03*
X1236750D03*
X1230844Y84764D03*
X1221986D03*
X1219033Y82008D03*
X1221986Y99725D03*
X1230844D03*
X1219033Y96969D03*
X1227891D03*
X1224939Y94213D03*
X1233797D03*
X1236750Y96969D03*
X1216080Y79252D03*
Y94213D03*
X1213128Y84764D03*
Y99725D03*
X1265293Y54843D03*
X1274151D03*
X1262340Y52087D03*
X1271198D03*
X1280057D03*
X1268246Y49331D03*
X1277104D03*
X1265293Y69803D03*
X1274151D03*
X1262340Y67048D03*
X1271198D03*
X1280057D03*
X1268246Y64292D03*
X1277104D03*
X1256435Y54843D03*
X1259387Y49331D03*
Y64292D03*
X1256435Y69803D03*
X1268246Y79252D03*
X1277104D03*
X1271198Y82008D03*
X1280057D03*
X1274151Y84764D03*
X1265293D03*
X1262340Y82008D03*
X1265293Y99725D03*
X1274151D03*
X1262340Y96969D03*
X1271198D03*
X1268246Y94213D03*
X1277104D03*
X1280057Y96969D03*
X1259387Y79252D03*
Y94213D03*
X1256435Y84764D03*
Y99725D03*
G54D38*
G01X857500Y778250D02*
X856770D01*
X854560Y780460D01*
Y782690D01*
X122700Y476100D03*
Y478400D03*
X122600Y473800D03*
Y471500D03*
X121673Y491672D03*
X130985Y504300D03*
X124822Y504271D03*
X127973Y504272D03*
X121673Y497973D03*
Y494822D03*
X118524Y491672D03*
X118500Y504238D03*
X115373Y504271D03*
X127973Y510571D03*
X124823D03*
X121673D03*
X131121Y513721D03*
X121673D03*
X131121Y510570D03*
X127971Y513721D03*
X124821D03*
X127971Y494823D03*
X131122Y491674D03*
X127973Y488524D03*
X131122D03*
Y485374D03*
X121673Y504272D03*
X124823Y501122D03*
X121673D03*
X127973Y497973D03*
X124822Y488523D03*
X127973Y491674D03*
X124823Y497973D03*
Y491674D03*
X127973Y485374D03*
X124823Y494822D03*
X131121Y494823D03*
X127973Y501122D03*
Y529469D03*
X124823Y523170D03*
Y542067D03*
X127973Y532618D03*
Y542067D03*
X124823Y532617D03*
X124822Y545216D03*
X131122Y532618D03*
X124823Y535766D03*
X127973Y538918D03*
X127996Y535781D03*
X121673Y545215D03*
Y523170D03*
X131121Y529467D03*
Y520018D03*
X127971D03*
X131121Y523168D03*
X124822Y520019D03*
X121673Y520020D03*
X115374Y529467D03*
X118524D03*
X121673D03*
X124823D03*
X121673Y532617D03*
X124822Y538917D03*
X121673Y535766D03*
X127973Y523170D03*
X121673Y538916D03*
X126869Y577770D03*
X122547Y564452D03*
Y558100D03*
Y551748D03*
X121601Y574686D03*
X126801Y574386D03*
X124900Y559638D03*
X124847Y550110D03*
X124900Y556462D03*
Y565990D03*
Y562814D03*
Y553286D03*
X122547Y561276D03*
Y554924D03*
Y567628D03*
X131369Y610945D03*
X115622Y604646D03*
X121911Y614076D03*
X131369Y588898D03*
X121922Y592048D03*
X118771Y595196D03*
X125072Y610945D03*
X125070Y598347D03*
X131370Y601496D03*
X118773Y601495D03*
X126646Y606400D03*
X115622Y614094D03*
Y601496D03*
X121922Y610945D03*
X128220Y614095D03*
X118773Y604645D03*
X125070Y614095D03*
X118773Y598345D03*
X118805Y614099D03*
X115623Y598345D03*
X118773Y610945D03*
X131369Y614095D03*
X118773Y589748D03*
X128221Y610945D03*
X121922Y588872D03*
X118773Y592048D03*
X121922Y617244D03*
X128221D03*
X131369D03*
X118771D03*
X125070D03*
X125072Y620392D03*
X121921D03*
X140571Y491674D03*
X140570Y488523D03*
X162618Y485374D03*
X150020Y491674D03*
X156319Y485374D03*
X146870Y491674D03*
Y482225D03*
X150020Y510571D03*
X153169D03*
X146870D03*
X153169Y513721D03*
X146870D03*
X150020D03*
X143721Y491674D03*
Y488524D03*
Y485374D03*
X140569Y494823D03*
X134270Y510571D03*
Y504272D03*
X146869Y494823D03*
X153168D03*
X159467D03*
X165768Y488524D03*
X153170Y491674D03*
X150020Y485374D03*
Y482225D03*
X146870Y485374D03*
Y488524D03*
X162618D03*
Y491674D03*
X134272D03*
X165768D03*
X134272Y488524D03*
Y485374D03*
X137421Y491674D03*
Y485374D03*
X140571D03*
X156318Y488523D03*
X156319Y491674D03*
X153169Y485374D03*
Y488524D03*
X159469Y491674D03*
Y488524D03*
Y485374D03*
X150020Y488524D03*
X137421D03*
X165766Y542066D03*
X143721Y532618D03*
X146870Y516870D03*
X150020D03*
X153169D03*
X137421Y535768D03*
Y542066D03*
X134270Y538916D03*
X137421Y532618D03*
X134272Y542066D03*
Y535768D03*
X140570Y535767D03*
X137421Y538918D03*
X153188Y538899D03*
X162617Y535766D03*
X146869Y538954D03*
X146858Y535742D03*
X159449Y542048D03*
Y538898D03*
X159456Y532642D03*
X162617Y542066D03*
Y538916D03*
X149981Y538917D03*
X153132Y535767D03*
X149985Y535771D03*
X153194Y542078D03*
X153187Y532636D03*
X140571Y532618D03*
X143718Y538953D03*
X143686Y542070D03*
X146869Y529469D03*
X134270Y523170D03*
X153168Y529469D03*
X140569D03*
X134270Y516869D03*
X159467Y529469D03*
X134272Y532618D03*
X162618D03*
X165766Y538916D03*
X151989Y552538D03*
X147451Y554136D03*
X142951Y553336D03*
X161280Y553800D03*
Y561700D03*
Y564000D03*
X147451Y551836D03*
Y549536D03*
X142951Y551036D03*
X161280Y566300D03*
X159537Y548256D03*
X147451Y556436D03*
X142951Y555636D03*
X160700Y551356D03*
X151989Y557138D03*
X161280Y556100D03*
X151989Y554838D03*
X161280Y558400D03*
X143968Y614095D03*
X143967Y610945D03*
X137669Y604645D03*
X162865Y595196D03*
Y604645D03*
X156566Y610945D03*
X159716Y598345D03*
X153417Y614095D03*
X150269D03*
X153418Y595197D03*
X162865Y610945D03*
X137661Y614096D03*
X137670Y595197D03*
X147143Y595184D03*
X137669Y610945D03*
Y601495D03*
X140818D03*
X134521Y595196D03*
X134519Y614095D03*
X150269Y598347D03*
X156566Y614095D03*
X143968Y601495D03*
X140821Y614106D03*
X166016Y601496D03*
X159716Y610945D03*
Y614095D03*
Y595197D03*
X166016Y610944D03*
X162867Y614095D03*
X147115Y598360D03*
X150268Y601496D03*
X147141Y614096D03*
X143968Y588898D03*
X153417Y610945D03*
X159716Y604645D03*
X166015Y598345D03*
X147117Y610945D03*
X162865Y601495D03*
X150268Y610944D03*
X159716Y601495D03*
X140818Y610945D03*
X134520Y610944D03*
X153418Y592048D03*
X159716D03*
X134521Y598345D03*
X143968Y592048D03*
X147117Y601495D03*
X143969Y617244D03*
X162881Y617266D03*
X153417Y617244D03*
X150251Y617226D03*
X134521Y617266D03*
X137671D03*
X140821D03*
X156566Y617244D03*
X159716D03*
X150351Y620436D03*
X181514Y479075D03*
X172065Y513721D03*
X175215D03*
X178365Y510571D03*
X175215D03*
X172065D03*
Y501122D03*
X178365Y507422D03*
X175215D03*
Y491674D03*
Y497973D03*
X172065Y491674D03*
X175215Y485374D03*
X175217Y482225D03*
X175215Y501122D03*
X178365D03*
X184664Y485372D03*
X172065Y494823D03*
X178365Y491674D03*
X181514Y488524D03*
X184664Y488522D03*
X175215Y494823D03*
X172065Y497973D03*
X178365Y494823D03*
X172065Y485374D03*
X172067Y482225D03*
X178365Y497973D03*
X172065Y504272D03*
X175216Y504271D03*
X172065Y507422D03*
X178365Y504272D03*
X168916Y510571D03*
Y504272D03*
X178365Y513721D03*
X172065Y488524D03*
X175216Y488523D03*
X178365Y485374D03*
Y488524D03*
X181514Y485374D03*
X178365Y520020D03*
X181514D03*
X172065Y535768D03*
Y526319D03*
X178365Y529469D03*
X175215D03*
X172065D03*
X175215Y523170D03*
X178365D03*
X175216Y535767D03*
X184664Y516869D03*
X172065Y523170D03*
Y520020D03*
X175216Y520019D03*
X168916Y523170D03*
Y516870D03*
X184665Y520019D03*
X178365Y526319D03*
X175215D03*
Y532618D03*
X178365Y535768D03*
X172065Y532618D03*
X175215Y538918D03*
X168916Y535766D03*
X172065Y538918D03*
X168916Y542066D03*
Y538916D03*
X178365Y532618D03*
X874410Y127953D03*
Y139764D03*
Y131890D03*
Y120079D03*
Y124016D03*
Y163386D03*
Y155512D03*
Y147638D03*
Y202755D03*
Y206692D03*
Y194881D03*
Y183071D03*
Y242125D03*
Y238188D03*
Y230314D03*
Y222440D03*
Y214566D03*
Y257873D03*
Y253936D03*
Y249999D03*
Y246062D03*
X894095Y131890D03*
X898032Y139764D03*
Y131890D03*
Y135827D03*
X905906Y127953D03*
X894095Y139764D03*
X905906Y124016D03*
Y120079D03*
Y116142D03*
X901969Y124016D03*
X894095D03*
X890158Y127953D03*
X901969D03*
X898032D03*
X894095D03*
X882284Y139764D03*
X886221Y135827D03*
X882284Y131890D03*
X886221Y124016D03*
X878347D03*
X886221Y127953D03*
X882284D03*
X878347D03*
X901969Y139764D03*
Y135827D03*
Y131890D03*
X886221Y139764D03*
X890158Y135827D03*
X886221Y131890D03*
X890158Y139764D03*
X894095Y135827D03*
X890158Y131890D03*
X878347Y135827D03*
Y116142D03*
X882284Y120079D03*
X886221Y116142D03*
X890158Y120079D03*
X894095Y116142D03*
X898032Y120079D03*
X901969Y116142D03*
X878347Y139764D03*
X882284Y135827D03*
X878347Y131890D03*
Y120079D03*
X882300Y124032D03*
X886221Y120079D03*
X890158Y124016D03*
X894095Y120079D03*
X898032Y124016D03*
X901969Y120079D03*
X905906Y139764D03*
Y135827D03*
Y131890D03*
X894095Y163386D03*
X898032D03*
Y167323D03*
Y171260D03*
Y175197D03*
X901969Y163386D03*
X905906D03*
X898032Y143701D03*
Y147638D03*
Y151575D03*
Y155512D03*
Y159449D03*
X886221Y171260D03*
X901969Y167323D03*
X905906D03*
X901969Y171260D03*
X905906D03*
X901969Y175197D03*
X905906D03*
X890158Y163386D03*
X894095Y167323D03*
Y175197D03*
X905906Y159449D03*
X901969D03*
X894095Y155512D03*
Y147638D03*
X882284Y167323D03*
X886221Y163386D03*
X882284D03*
X878347D03*
X886221Y159449D03*
X882284Y155512D03*
X886221Y151575D03*
X882284Y147638D03*
X886221Y143701D03*
X901969Y147638D03*
Y143701D03*
X890158Y159449D03*
X886221Y155512D03*
X890158Y151575D03*
X886221Y147638D03*
X890158Y143701D03*
X894095Y159449D03*
X890158Y155512D03*
X894095Y151575D03*
X890158Y147638D03*
X894095Y143701D03*
X878347Y159449D03*
Y151575D03*
Y143701D03*
X882284Y159449D03*
X878347Y155512D03*
X882284Y151575D03*
X878347Y147638D03*
X882284Y143701D03*
X905906Y155512D03*
Y151575D03*
Y147638D03*
Y143701D03*
X901969Y155512D03*
Y151575D03*
X898032Y194881D03*
Y198818D03*
Y202755D03*
X894095D03*
X898032Y179134D03*
Y183071D03*
Y190944D03*
X905906Y183071D03*
X901969D03*
Y194881D03*
X905906D03*
X901969Y198818D03*
X905906D03*
X901969Y202755D03*
X905906D03*
X901969Y206692D03*
X905906D03*
X890158Y202755D03*
X898032Y206692D03*
X894095D03*
Y194881D03*
X901969Y179134D03*
X905906D03*
X901969Y190944D03*
X905906D03*
X894095Y183071D03*
X882284Y206692D03*
X886221Y202755D03*
X882284D03*
X878347D03*
X886221Y198818D03*
X882284Y194881D03*
X886221Y190944D03*
Y179134D03*
Y206692D03*
X890158Y198818D03*
X886221Y194881D03*
X890158Y190944D03*
X886221Y183071D03*
X890158Y179134D03*
Y206692D03*
X894095Y198818D03*
X890158Y194881D03*
X894095Y190944D03*
X890158Y183071D03*
X894095Y179134D03*
X878347Y198818D03*
Y190944D03*
Y206692D03*
X882284Y198818D03*
X878347Y194881D03*
X882284Y190944D03*
X878347Y183071D03*
X898032Y238188D03*
X894095D03*
X898032Y234251D03*
Y230314D03*
X905906Y238188D03*
X901969D03*
X898032Y226377D03*
Y222440D03*
Y218503D03*
Y214566D03*
Y210629D03*
X901969Y222440D03*
X905906D03*
X901969Y226377D03*
X905906D03*
Y234251D03*
X901969Y230314D03*
X905906D03*
X901969Y234251D03*
X894095Y222440D03*
X890158Y238188D03*
X894095Y242125D03*
Y230314D03*
X901969Y242125D03*
Y210629D03*
X905906D03*
X901969Y214566D03*
X905906D03*
X901969Y218503D03*
X905906D03*
X894095Y214566D03*
X886221Y226377D03*
X882284Y222440D03*
X886221Y242125D03*
X878347D03*
X886221Y238188D03*
X882284D03*
X878347D03*
X886221Y234251D03*
X882284Y230314D03*
X886221Y218503D03*
X882284Y214566D03*
X886221Y210629D03*
X890158Y234251D03*
X886221Y230314D03*
X890158Y226377D03*
X886221Y222440D03*
X890158Y218503D03*
X886221Y214566D03*
X890158Y210629D03*
X905906Y242125D03*
X898032D03*
X890158D03*
X882284D03*
X894095Y234251D03*
X890158Y230314D03*
X894095Y226377D03*
X890158Y222440D03*
X894095Y218503D03*
X890158Y214566D03*
X894095Y210629D03*
X878347Y234251D03*
Y226377D03*
Y218503D03*
Y210629D03*
X882284Y234251D03*
X878347Y230314D03*
X882284Y226377D03*
X878347Y222440D03*
X882284Y218503D03*
X878347Y214566D03*
X882284Y210629D03*
X901969Y253936D03*
X894095D03*
X890158Y249999D03*
X905906D03*
X898032D03*
X878347Y253936D03*
X886221D03*
X882284Y249999D03*
X905906Y246062D03*
X901969Y249999D03*
X898032Y246062D03*
X894095Y249999D03*
X890158Y246062D03*
X886221Y249999D03*
X882284Y246062D03*
X878347Y249999D03*
X901969Y246062D03*
X894095D03*
X886221D03*
X878347D03*
X905906Y257873D03*
X901969Y261810D03*
X898032Y257873D03*
X894095Y261810D03*
X890158Y257873D03*
X886221Y261810D03*
X882284Y257873D03*
X878347Y261810D03*
X905906Y253936D03*
X901969Y257873D03*
X898032Y253936D03*
X894095Y257873D03*
X890158Y253936D03*
X886221Y257873D03*
X882284Y253936D03*
X878347Y257873D03*
X909843Y131890D03*
X941339Y127953D03*
X913780Y131890D03*
Y127953D03*
Y139764D03*
X921654Y127953D03*
X929528D03*
X937402Y139764D03*
Y127953D03*
X941339Y139764D03*
X933465D03*
X921654Y135827D03*
X941339Y124016D03*
Y120079D03*
Y116142D03*
X937402Y124016D03*
X933465Y127953D03*
X929528Y124016D03*
X925591Y127953D03*
X921654Y124016D03*
X917717Y127953D03*
X909843Y135827D03*
X913780Y124016D03*
X909843Y127953D03*
X921654Y139764D03*
X929528D03*
X925591D03*
X921654Y131890D03*
X941339D03*
Y135827D03*
X933465Y131890D03*
Y135827D03*
X937402Y131890D03*
Y135827D03*
X929528Y131890D03*
Y135827D03*
X925591Y131890D03*
Y135827D03*
X909843Y120079D03*
X913780Y116142D03*
X917717Y120079D03*
X921654Y116142D03*
X925591Y120079D03*
X929528Y116142D03*
X933465Y120079D03*
X937402Y116142D03*
X909843Y124016D03*
X913780Y120079D03*
X917717Y124016D03*
X921654Y120079D03*
X925591Y124016D03*
X929528Y120079D03*
X933465Y124016D03*
X937402Y120079D03*
X913780Y135827D03*
X917717Y139764D03*
Y131890D03*
Y135827D03*
X909843Y139764D03*
X937402Y155512D03*
X941339Y151575D03*
Y155512D03*
X929528Y159449D03*
X913780Y143701D03*
Y159449D03*
X937402Y175197D03*
X941339Y171260D03*
X937402Y167323D03*
X941339Y163386D03*
X929528Y175197D03*
X933465Y171260D03*
X929528Y167323D03*
X933465Y163386D03*
X925591Y171260D03*
X921654Y175197D03*
X925591Y163386D03*
X921654Y167323D03*
X917717Y163386D03*
Y171260D03*
X921654Y159449D03*
X937402D03*
X925591Y151575D03*
X913780Y147638D03*
X917717Y159449D03*
X913780Y155512D03*
Y151575D03*
X941339Y175197D03*
Y167323D03*
X933465Y175197D03*
X937402Y171260D03*
X933465Y167323D03*
X937402Y163386D03*
X929528Y171260D03*
X925591Y175197D03*
X921654Y163386D03*
X925591Y167323D03*
X917717D03*
X921654Y171260D03*
X917717Y175197D03*
X929528Y163386D03*
X941339Y159449D03*
X937402Y151575D03*
X933465Y159449D03*
X925591D03*
X921654Y147638D03*
X909843Y163386D03*
X913780D03*
X909843Y167323D03*
X913780D03*
X909843Y171260D03*
X913780D03*
X909843Y175197D03*
X913780D03*
X909843Y147638D03*
X933465Y151575D03*
Y155512D03*
X921654Y151575D03*
X929528D03*
Y155512D03*
X925591Y143701D03*
Y147638D03*
Y155512D03*
X909843Y159449D03*
Y143701D03*
Y155512D03*
X941339Y143701D03*
Y147638D03*
X933465Y143701D03*
Y147638D03*
X937402Y143701D03*
Y147638D03*
X929528Y143701D03*
Y147638D03*
X917717Y155512D03*
Y151575D03*
Y143701D03*
Y147638D03*
X921654Y155512D03*
X917717Y179134D03*
X913780Y183071D03*
X921654Y194881D03*
X917717Y198818D03*
X937402Y194881D03*
X933465Y198818D03*
X929528Y202755D03*
X925591Y206692D03*
X929528Y194881D03*
X925591Y198818D03*
X921654Y202755D03*
X917717Y206692D03*
X933465D03*
X937402Y202755D03*
X941339Y198818D03*
Y206692D03*
X925591Y190944D03*
X933465Y179134D03*
X929528Y183071D03*
X925591Y179134D03*
X921654Y183071D03*
X941339Y190944D03*
X933465D03*
X937402Y183071D03*
X941339Y179134D03*
X917717Y190944D03*
X925591Y194881D03*
X921654Y198818D03*
X917717Y202755D03*
X937402Y206692D03*
X941339Y202755D03*
Y194881D03*
X937402Y198818D03*
X933465Y202755D03*
X929528Y206692D03*
X933465Y194881D03*
X929528Y198818D03*
X925591Y202755D03*
X921654Y206692D03*
X917717Y194881D03*
X937402Y179134D03*
X933465Y183071D03*
X929528Y190944D03*
Y179134D03*
X925591Y183071D03*
X921654Y179134D03*
X937402Y190944D03*
X917717Y183071D03*
X921654Y190944D03*
X909843Y194881D03*
X913780D03*
X909843Y198818D03*
X913780D03*
X909843Y202755D03*
X913780D03*
X909843Y206692D03*
X913780D03*
X909843Y179134D03*
X913780D03*
X909843Y183071D03*
Y190944D03*
X913780D03*
X921654Y238188D03*
X917717D03*
Y214566D03*
X913780Y238188D03*
X909843D03*
X913780Y214566D03*
X941339Y226377D03*
X937402Y222440D03*
X933465Y226377D03*
X929528Y222440D03*
X925591Y226377D03*
X929528Y230314D03*
X937402D03*
X941339Y234251D03*
X937402Y238188D03*
X933465Y234251D03*
X929528Y238188D03*
X925591Y234251D03*
X921654Y210629D03*
X925591Y214566D03*
X929528Y210629D03*
X941339Y214566D03*
X933465D03*
X937402Y210629D03*
X917717Y222440D03*
Y226377D03*
X921654Y222440D03*
Y226377D03*
X917717Y230314D03*
Y234251D03*
X921654Y230314D03*
Y234251D03*
X925591Y230314D03*
Y222440D03*
X933465D03*
X941339D03*
X937402Y226377D03*
X929528D03*
X941339Y238188D03*
Y230314D03*
X937402Y242125D03*
Y234251D03*
X933465Y238188D03*
Y230314D03*
X929528Y242125D03*
Y234251D03*
X925591Y238188D03*
X921654Y242125D03*
X929528Y214566D03*
X933465Y210629D03*
X925591D03*
X917717D03*
X921654Y218503D03*
X925591D03*
X929528D03*
X933465D03*
X937402D03*
X941339D03*
X921654Y214566D03*
X917717Y218503D03*
X937402Y214566D03*
X913780Y226377D03*
X909843Y222440D03*
X913780D03*
X909843Y226377D03*
Y230314D03*
Y234251D03*
X913780Y230314D03*
Y234251D03*
Y242125D03*
X909843D03*
Y214566D03*
Y210629D03*
X913780D03*
X909843Y218503D03*
X913780D03*
X941339Y242125D03*
X933465D03*
X925591D03*
X917717D03*
X937402Y253936D03*
X929528D03*
X921654D03*
X941339Y249999D03*
X933465D03*
X925591D03*
X917717D03*
X913780Y253936D03*
X909843Y261810D03*
Y257873D03*
Y253936D03*
Y249999D03*
Y246062D03*
X941339D03*
X937402Y249999D03*
X933465Y246062D03*
X929528Y249999D03*
X925591Y246062D03*
X921654Y249999D03*
X917717Y246062D03*
X913780Y249999D03*
X937402Y246062D03*
X929528D03*
X921654D03*
X913780D03*
X941339Y257873D03*
X937402Y261810D03*
X933465Y257873D03*
X929528Y261810D03*
X925591Y257873D03*
X921654Y261810D03*
X917717Y257873D03*
X913780Y261810D03*
X941339Y253936D03*
X937402Y257873D03*
X933465Y253936D03*
X929528Y257873D03*
X925591Y253936D03*
X921654Y257873D03*
X917717Y253936D03*
X913780Y257873D03*
X953149Y127953D03*
X949212D03*
Y139764D03*
X957086Y127953D03*
X964960D03*
X972834D03*
X957086Y139764D03*
X953149Y135827D03*
X968897Y139764D03*
X953149Y124016D03*
Y120079D03*
Y116142D03*
X972834Y124016D03*
X968897Y127953D03*
X964960Y124016D03*
X961023Y127953D03*
X957086Y124016D03*
X972834Y139764D03*
X953149D03*
Y131890D03*
X957086D03*
X964960D03*
X961023Y139764D03*
Y131890D03*
Y135827D03*
X957086D03*
Y116142D03*
X961023Y120079D03*
X964960Y116142D03*
X968897Y120079D03*
X972834Y116142D03*
X957086Y120079D03*
X961023Y124016D03*
X964960Y120079D03*
X968897Y124016D03*
X972834Y120079D03*
Y135827D03*
Y131890D03*
X964960Y135827D03*
Y139764D03*
X968897Y135827D03*
Y131890D03*
X949212Y155512D03*
X953149Y163386D03*
X949212Y167323D03*
X964960D03*
X968897Y163386D03*
X957086Y175197D03*
X961023Y171260D03*
X953149D03*
X949212Y175197D03*
X961023Y163386D03*
X957086Y167323D03*
X972834D03*
X968897Y171260D03*
X964960Y175197D03*
X972834D03*
X968897Y151575D03*
X964960Y159449D03*
X957086D03*
X953149Y151575D03*
X949212Y159449D03*
X972834D03*
X953149Y167323D03*
X957086Y163386D03*
X949212Y171260D03*
Y163386D03*
X972834Y171260D03*
X968897Y175197D03*
X972834Y163386D03*
X968897Y167323D03*
X964960Y171260D03*
X961023Y175197D03*
Y167323D03*
X964960Y163386D03*
X953149Y175197D03*
X957086Y171260D03*
X953149Y159449D03*
X949212Y151575D03*
X972834Y147638D03*
X968897Y159449D03*
X961023D03*
Y147638D03*
X972834Y151575D03*
X957086Y143701D03*
X961023D03*
X957086Y151575D03*
Y147638D03*
Y155512D03*
X953149Y143701D03*
Y155512D03*
X949212Y143701D03*
Y147638D03*
X964960Y143701D03*
X961023Y155512D03*
Y151575D03*
X964960Y155512D03*
Y151575D03*
X968897Y155512D03*
X964960Y147638D03*
X968897D03*
Y143701D03*
X972834D03*
Y155512D03*
X949212Y194881D03*
X968897Y198818D03*
X964960Y202755D03*
X961023Y206692D03*
X972834Y194881D03*
X953149Y206692D03*
X964960Y194881D03*
X961023Y198818D03*
X957086Y202755D03*
X949212D03*
X953149Y198818D03*
X957086Y194881D03*
X972834Y202755D03*
X968897Y206692D03*
X949212Y183071D03*
X953149Y179134D03*
X961023D03*
X957086Y183071D03*
X953149Y190944D03*
X968897D03*
X972834Y183071D03*
X961023Y190944D03*
X964960Y183071D03*
X968897Y179134D03*
X964960Y198818D03*
X961023Y202755D03*
X957086Y206692D03*
X968897Y194881D03*
X953149D03*
X949212Y198818D03*
Y206692D03*
X953149Y202755D03*
X961023Y194881D03*
X957086Y198818D03*
X972834Y206692D03*
Y198818D03*
X968897Y202755D03*
X964960Y206692D03*
X972834Y190944D03*
X964960Y179134D03*
X961023Y183071D03*
X957086Y190944D03*
X953149Y183071D03*
X957086Y179134D03*
X949212D03*
X964960Y190944D03*
X968897Y183071D03*
X972834Y179134D03*
Y238188D03*
X968897Y226377D03*
Y234251D03*
X953149Y226377D03*
X949212Y222440D03*
Y230314D03*
X964960Y222440D03*
X961023Y226377D03*
X957086Y222440D03*
X964960Y230314D03*
X957086D03*
X953149Y234251D03*
X949212Y238188D03*
X964960D03*
X961023Y234251D03*
X957086Y238188D03*
X953149Y214566D03*
X957086Y210629D03*
X949212D03*
X972834D03*
X968897Y214566D03*
X961023D03*
X964960Y210629D03*
X972834Y222440D03*
Y226377D03*
Y230314D03*
Y234251D03*
X968897Y230314D03*
Y222440D03*
X953149D03*
X961023D03*
X972834Y242125D03*
X949212Y226377D03*
X964960D03*
X957086D03*
X953149Y238188D03*
Y230314D03*
X949212Y242125D03*
Y234251D03*
X968897Y238188D03*
X964960Y242125D03*
Y234251D03*
X961023Y238188D03*
Y230314D03*
X957086Y242125D03*
Y234251D03*
X949212Y214566D03*
X953149Y210629D03*
X968897D03*
X964960Y214566D03*
X972834Y218503D03*
X949212D03*
X953149D03*
X957086Y214566D03*
X961023Y210629D03*
X972834Y214566D03*
X957086Y218503D03*
X961023D03*
X964960D03*
X968897D03*
Y242125D03*
X961023D03*
X953149D03*
X972834Y253936D03*
X949212Y261810D03*
Y257873D03*
Y253936D03*
X964960D03*
X957086D03*
X953149Y249999D03*
X949212D03*
Y246062D03*
X968897Y249999D03*
X961023D03*
X972834D03*
X968897Y246062D03*
X964960Y249999D03*
X961023Y246062D03*
X957086Y249999D03*
X953149Y246062D03*
X972834D03*
X964960D03*
X957086D03*
X972834Y261810D03*
X968897Y257873D03*
X964960Y261810D03*
X961023Y257873D03*
X957086Y261810D03*
X953149Y257873D03*
X972834D03*
X968897Y253936D03*
X964960Y257873D03*
X961023Y253936D03*
X957086Y257873D03*
X953149Y253936D03*
X992519Y139764D03*
X996456D03*
Y131890D03*
Y135827D03*
X1000393Y131890D03*
X980708Y127953D03*
Y139764D03*
X1008267Y135827D03*
Y127953D03*
Y124016D03*
X984645Y135827D03*
X1000393Y139764D03*
X992519Y127953D03*
Y124016D03*
X988582Y127953D03*
Y124016D03*
Y120079D03*
Y116142D03*
X984645Y127953D03*
X980708Y124016D03*
X996456Y127953D03*
X1000393Y124016D03*
Y127953D03*
X1004330D03*
X976771D03*
X980708Y135827D03*
Y131890D03*
X1008267Y139764D03*
X976771Y120079D03*
X980708Y116142D03*
X984645Y120079D03*
X1008267Y131890D03*
X1004330Y135827D03*
Y139764D03*
X976771Y124016D03*
X980708Y120079D03*
X984645Y124016D03*
X1004330Y131890D03*
X1000393Y135827D03*
X992519Y115742D03*
X996456Y120079D03*
X1000393Y116142D03*
X1004330Y120079D03*
X1008267Y116142D03*
X992519Y120079D03*
X996456Y124016D03*
X1000393Y120079D03*
X1004330Y124016D03*
X1008267Y120079D03*
X988582Y139764D03*
Y135827D03*
X984645Y131890D03*
X976771D03*
Y139764D03*
X988582Y131890D03*
X984645Y139764D03*
X976771Y135827D03*
X996456Y163386D03*
X1000393D03*
X996456Y167323D03*
Y171260D03*
Y175197D03*
X992519Y163386D03*
X988582D03*
X980708Y175197D03*
X996456Y143701D03*
Y147638D03*
Y151575D03*
Y155512D03*
Y159449D03*
X976771Y163386D03*
Y171260D03*
X1008267Y163386D03*
Y171260D03*
Y159449D03*
Y143701D03*
Y151575D03*
X980708Y163386D03*
X984645D03*
X988582Y167323D03*
X992519D03*
X980708D03*
X984645D03*
X988582Y171260D03*
X992519D03*
X980708D03*
X984645D03*
X988582Y175197D03*
X992519D03*
X984645D03*
X1000393Y167323D03*
X1004330Y163386D03*
X1000393Y175197D03*
X988582Y159449D03*
X992519D03*
X984645Y147638D03*
X1000393D03*
Y155512D03*
X976771Y167323D03*
Y175197D03*
X980708Y159449D03*
Y155512D03*
X976771Y151575D03*
X1004330Y143701D03*
X1008267Y147638D03*
X1004330Y151575D03*
X1008267Y155512D03*
X1004330Y159449D03*
X1008267Y167323D03*
X1004330Y171260D03*
X1008267Y175197D03*
X1000393Y143701D03*
X1004330Y147638D03*
X1000393Y151575D03*
X1004330Y155512D03*
X1000393Y159449D03*
X1004330Y167323D03*
X1000393Y171260D03*
X1004330Y175197D03*
X988582Y147638D03*
Y143701D03*
X984645Y155512D03*
Y151575D03*
Y143701D03*
X988582Y151575D03*
X976771Y147638D03*
X980708Y143701D03*
X976771Y155512D03*
X980708Y147638D03*
Y151575D03*
X976771Y159449D03*
Y143701D03*
X996456Y194881D03*
Y198818D03*
Y202755D03*
X1000393D03*
X996456Y179134D03*
Y183071D03*
Y190944D03*
X992519Y183071D03*
X988582D03*
X976771Y179134D03*
X980708Y183071D03*
X976771Y206692D03*
Y198818D03*
Y190944D03*
X1008267Y202755D03*
Y198818D03*
Y190944D03*
Y179134D03*
X980708Y198818D03*
X988582Y194881D03*
X992519D03*
X980708D03*
X984645D03*
X988582Y198818D03*
X992519D03*
X984645D03*
X988582Y202755D03*
X992519D03*
X980708D03*
X984645D03*
X988582Y206692D03*
X992519D03*
X980708D03*
X984645D03*
X1000393D03*
X996456D03*
X1004330Y202755D03*
X1000393Y194881D03*
X988582Y179134D03*
X992519D03*
X988582Y190944D03*
X992519D03*
X980708D03*
X984645D03*
X980708Y179134D03*
X984645D03*
Y183071D03*
X1000393D03*
X976771Y202755D03*
Y194881D03*
Y183071D03*
X1004330Y179134D03*
X1008267Y183071D03*
X1004330Y190944D03*
X1008267Y194881D03*
X1004330Y198818D03*
X1008267Y206692D03*
X1000393Y179134D03*
X1004330Y183071D03*
X1000393Y190944D03*
X1004330Y194881D03*
X1000393Y198818D03*
X1004330Y206692D03*
X992519Y238188D03*
X988582D03*
X984645D03*
X980708D03*
X1000393D03*
X996456D03*
Y234251D03*
Y230314D03*
Y226377D03*
Y222440D03*
Y218503D03*
Y214566D03*
Y210629D03*
X976771Y238188D03*
Y214566D03*
X980708D03*
X1008267Y226377D03*
Y242125D03*
Y238188D03*
Y234251D03*
Y218503D03*
Y210629D03*
X1000393Y222440D03*
X988582D03*
X992519D03*
X980708D03*
X984645D03*
X988582Y226377D03*
X992519D03*
X984645D03*
X980708D03*
X988582Y230314D03*
X992519D03*
Y234251D03*
X980708Y230314D03*
Y234251D03*
X984645Y230314D03*
Y234251D03*
X988582D03*
X1000393Y230314D03*
X1004330Y238188D03*
X1000393Y242125D03*
X980708D03*
X984645D03*
X992519D03*
X984645Y214566D03*
X988582Y210629D03*
X992519D03*
X980708D03*
X984645D03*
X988582Y214566D03*
X992519D03*
X988582Y218503D03*
X992519D03*
X980708D03*
X984645D03*
X1000393Y214566D03*
X976771Y222440D03*
Y226377D03*
Y230314D03*
Y234251D03*
Y210629D03*
Y218503D03*
X1004330Y210629D03*
X1008267Y214566D03*
X1004330Y218503D03*
X1008267Y222440D03*
X1004330Y226377D03*
X1008267Y230314D03*
X1004330Y234251D03*
X1000393Y210629D03*
X1004330Y214566D03*
X1000393Y218503D03*
X1004330Y222440D03*
X1000393Y226377D03*
X1004330Y230314D03*
X1000393Y234251D03*
X1004330Y242125D03*
X996456D03*
X988582D03*
X976771D03*
X1008267Y253936D03*
X980708D03*
X984645D03*
Y257873D03*
Y261810D03*
X992519Y253936D03*
X1000393D03*
X984645Y246062D03*
Y249999D03*
X988582D03*
X996456D03*
X1004330D03*
X976771D03*
X1008267D03*
X1004330Y246062D03*
X1000393Y249999D03*
X996456Y246062D03*
X992519Y249999D03*
X988582Y246062D03*
X980708Y249999D03*
X976771Y246062D03*
X1008267D03*
X1000393D03*
X992519D03*
X980708D03*
X1008267Y261810D03*
X1004330Y257873D03*
X1000393Y261810D03*
X996456Y257873D03*
X992519Y261810D03*
X988582Y257873D03*
X980708Y261810D03*
X976771Y257873D03*
X1008267D03*
X1004330Y253936D03*
X1000393Y257873D03*
X996456Y253936D03*
X992519Y257873D03*
X988582Y253936D03*
X980708Y257873D03*
X976771Y253936D03*
X1021751Y117469D03*
X1012204Y131890D03*
Y139764D03*
Y127953D03*
X1016141Y124016D03*
X1020078Y127953D03*
X1016141D03*
X1020078Y139764D03*
X1012204Y120079D03*
X1016141Y116142D03*
X1020078Y120079D03*
Y131890D03*
X1016141Y135827D03*
Y139764D03*
X1012204Y124016D03*
X1016141Y120079D03*
X1023278D03*
X1016141Y131890D03*
X1012204Y135827D03*
Y167323D03*
Y163386D03*
X1016141D03*
X1020078D03*
X1012204Y175197D03*
Y147638D03*
Y155512D03*
X1016141Y143701D03*
X1020078Y147638D03*
X1016141Y151575D03*
X1020078Y155512D03*
X1016141Y159449D03*
X1020078Y167323D03*
X1016141Y171260D03*
X1020078Y175197D03*
X1012204Y143701D03*
X1016141Y147638D03*
X1012204Y151575D03*
X1016141Y155512D03*
X1012204Y159449D03*
X1016141Y167323D03*
X1012204Y171260D03*
X1016141Y175197D03*
X1012204Y206692D03*
Y202755D03*
Y194881D03*
X1016141Y202755D03*
X1020078D03*
X1012204Y183071D03*
X1016141Y179134D03*
X1020078Y183071D03*
X1016141Y190944D03*
X1020078Y194881D03*
X1016141Y198818D03*
X1020078Y206692D03*
X1012204Y179134D03*
X1016141Y183071D03*
X1012204Y190944D03*
X1016141Y194881D03*
X1012204Y198818D03*
X1016141Y206692D03*
X1012204Y222440D03*
Y238188D03*
Y230314D03*
X1016141Y242125D03*
X1020078D03*
X1016141Y238188D03*
X1020078D03*
X1012204Y214566D03*
Y242125D03*
X1016141Y210629D03*
X1020078Y214566D03*
X1016141Y218503D03*
X1020078Y222440D03*
X1016141Y226377D03*
X1020078Y230314D03*
X1016141Y234251D03*
X1012204Y210629D03*
X1016141Y214566D03*
X1012204Y218503D03*
X1016141Y222440D03*
X1012204Y226377D03*
X1016141Y230314D03*
X1012204Y234251D03*
X1020078Y257873D03*
X1016141Y253936D03*
X1020078D03*
X1012204Y249999D03*
X1020078D03*
Y246062D03*
X1016141Y249999D03*
X1012204Y246062D03*
X1016141D03*
Y261810D03*
X1012204Y257873D03*
X1016141D03*
X1012204Y253936D03*
G54D75*
G01X145579Y-328699D02*
Y-346199D01*
X154313D01*
G01X167446Y-334533D02*
Y-346199D01*
G01Y-329866D02*
X167009Y-329574D01*
Y-328991D01*
X167446Y-328699D01*
X167883Y-328991D01*
Y-329574D01*
X167446Y-329866D01*
G01X181889Y-350574D02*
X183418Y-351741D01*
X185164Y-352032D01*
X186692Y-351741D01*
X188003Y-350283D01*
X188876Y-348241D01*
Y-334533D01*
G01Y-336866D02*
X188003Y-335699D01*
X186692Y-334824D01*
X185164Y-334533D01*
X183418Y-335116D01*
X182326Y-336282D01*
X181452Y-338324D01*
X181016Y-340366D01*
X181234Y-342116D01*
X182108Y-344158D01*
X183418Y-345616D01*
X185164Y-346199D01*
X186474Y-345907D01*
X188003Y-344741D01*
X188876Y-343575D01*
G01X198734Y-346199D02*
Y-328699D01*
G01Y-337157D02*
X199826Y-335699D01*
X200918Y-334824D01*
X202664Y-334533D01*
X203974Y-334824D01*
X205503Y-335991D01*
X206158Y-337741D01*
Y-346199D01*
G01X219946Y-328699D02*
Y-346199D01*
G01X216889Y-334533D02*
X223003D01*
G01X233734Y-346199D02*
Y-334533D01*
G01Y-337449D02*
X234608Y-335991D01*
X235918Y-334824D01*
X237664Y-334533D01*
X239192Y-334824D01*
X240503Y-335991D01*
X241158Y-338032D01*
Y-346199D01*
G01X254946Y-334533D02*
Y-346199D01*
G01Y-329866D02*
X254509Y-329574D01*
Y-328991D01*
X254946Y-328699D01*
X255383Y-328991D01*
Y-329574D01*
X254946Y-329866D01*
G01X268734Y-346199D02*
Y-334533D01*
G01Y-337449D02*
X269608Y-335991D01*
X270918Y-334824D01*
X272664Y-334533D01*
X274192Y-334824D01*
X275503Y-335991D01*
X276158Y-338032D01*
Y-346199D01*
G01X286889Y-350574D02*
X288418Y-351741D01*
X290164Y-352032D01*
X291692Y-351741D01*
X293003Y-350283D01*
X293876Y-348241D01*
Y-334533D01*
G01Y-336866D02*
X293003Y-335699D01*
X291692Y-334824D01*
X290164Y-334533D01*
X288418Y-335116D01*
X287326Y-336282D01*
X286452Y-338324D01*
X286016Y-340366D01*
X286234Y-342116D01*
X287108Y-344158D01*
X288418Y-345616D01*
X290164Y-346199D01*
X291474Y-345907D01*
X293003Y-344741D01*
X293876Y-343575D01*
G01X320579Y-346199D02*
Y-328699D01*
X325819D01*
X327566Y-329574D01*
X328876Y-331616D01*
X329313Y-333949D01*
X328876Y-336282D01*
X327784Y-338032D01*
X325819Y-338908D01*
X320579D01*
G01X346813Y-346199D02*
X338079D01*
Y-328699D01*
X346813D01*
G01X343319Y-337157D02*
X338079D01*
G01X361692Y-336866D02*
X362566Y-335991D01*
X363221Y-334533D01*
X363658Y-332490D01*
X363221Y-330741D01*
X362348Y-329574D01*
X360819Y-328699D01*
X354924D01*
Y-346199D01*
X362129D01*
X363658Y-345033D01*
X364531Y-343282D01*
X364968Y-341241D01*
X364531Y-339199D01*
X363221Y-337449D01*
X361692Y-336866D01*
X354924D01*
G01X390579Y-346199D02*
Y-328699D01*
X395819D01*
X397566Y-329574D01*
X398876Y-331616D01*
X399313Y-333949D01*
X398876Y-336282D01*
X397784Y-338032D01*
X395819Y-338908D01*
X390579D01*
G01X406769Y-346199D02*
Y-328699D01*
X412446Y-343282D01*
X418123Y-328699D01*
Y-346199D01*
G01X434749Y-330158D02*
X433439Y-329282D01*
X431911Y-328699D01*
X430164D01*
X428199Y-329574D01*
X426671Y-331032D01*
X425579Y-332783D01*
X424706Y-335699D01*
X424487Y-338324D01*
X424924Y-340949D01*
X425579Y-342699D01*
X426889Y-344449D01*
X428418Y-345616D01*
X429946Y-346199D01*
X431474D01*
X433003Y-345616D01*
X434313Y-344741D01*
X435405Y-343575D01*
G01X460579Y-346199D02*
Y-328699D01*
X465819D01*
X467566Y-329574D01*
X468876Y-331616D01*
X469313Y-333949D01*
X468876Y-336282D01*
X467784Y-338032D01*
X465819Y-338908D01*
X460579D01*
G01X476987Y-328699D02*
X482446Y-346199D01*
X487905Y-328699D01*
G01X499946D02*
Y-346199D01*
G01X494924Y-328699D02*
X504968D01*
G01X284269Y-301199D02*
Y-283699D01*
X289946Y-298282D01*
X295623Y-283699D01*
Y-301199D01*
G01X307446D02*
X306136Y-300907D01*
X304826Y-299741D01*
X303952Y-297699D01*
X303516Y-295366D01*
X303952Y-293032D01*
X304826Y-290991D01*
X306136Y-289824D01*
X307446Y-289533D01*
X308756Y-289824D01*
X310066Y-290991D01*
X310939Y-293032D01*
X311158Y-295366D01*
X310939Y-297699D01*
X310066Y-299741D01*
X308756Y-300907D01*
X307446Y-301199D01*
G01X328876Y-283699D02*
Y-301199D01*
G01Y-298575D02*
X328003Y-300033D01*
X326692Y-300907D01*
X325164Y-301199D01*
X323418Y-300616D01*
X322108Y-299158D01*
X321234Y-297408D01*
X321016Y-295366D01*
X321234Y-293324D01*
X322108Y-291574D01*
X323418Y-290116D01*
X325164Y-289533D01*
X326692Y-289824D01*
X327784Y-290408D01*
X328876Y-291574D01*
G01X339171Y-293324D02*
X346158D01*
X345503Y-291282D01*
X344411Y-290116D01*
X342883Y-289533D01*
X341354Y-289824D01*
X340044Y-290699D01*
X339171Y-292741D01*
X338734Y-294491D01*
Y-296241D01*
X339171Y-297991D01*
X340263Y-299741D01*
X341573Y-300907D01*
X343101Y-301199D01*
X344629Y-300616D01*
X346158Y-298866D01*
G01X359946Y-301199D02*
Y-283699D01*
G01X556346Y-346199D02*
Y-328699D01*
X553726Y-332199D01*
G01Y-346199D02*
X558966D01*
G01X569043Y-343575D02*
X570352Y-345033D01*
X571881Y-345907D01*
X573846Y-346199D01*
X575811Y-345616D01*
X577339Y-344449D01*
X578431Y-342408D01*
X578649Y-340074D01*
X578213Y-337741D01*
X577121Y-336282D01*
X575592Y-335116D01*
X574064Y-334824D01*
X572536Y-335116D01*
X570571Y-336282D01*
X571226Y-328699D01*
X577121D01*
G01X591346Y-346199D02*
Y-328699D01*
X588726Y-332199D01*
G01Y-346199D02*
X593966D01*
G01X608846Y-328699D02*
X607099Y-329282D01*
X605789Y-330741D01*
X604916Y-332490D01*
X604261Y-334824D01*
X604043Y-337449D01*
X604261Y-340074D01*
X604916Y-342408D01*
X605789Y-344158D01*
X607099Y-345616D01*
X608846Y-346199D01*
X610592Y-345616D01*
X611903Y-344158D01*
X612776Y-342408D01*
X613431Y-340074D01*
X613649Y-337449D01*
X613431Y-334824D01*
X612776Y-332490D01*
X611903Y-330741D01*
X610592Y-329282D01*
X608846Y-328699D01*
G01X621543Y-343575D02*
X622852Y-345033D01*
X624381Y-345907D01*
X626346Y-346199D01*
X628311Y-345616D01*
X629839Y-344449D01*
X630931Y-342408D01*
X631149Y-340074D01*
X630713Y-337741D01*
X629621Y-336282D01*
X628092Y-335116D01*
X626564Y-334824D01*
X625036Y-335116D01*
X623071Y-336282D01*
X623726Y-328699D01*
X629621D01*
G01X543229Y-301199D02*
Y-283699D01*
X548469D01*
X550216Y-284574D01*
X551526Y-286616D01*
X551963Y-288949D01*
X551526Y-291282D01*
X550434Y-293032D01*
X548469Y-293908D01*
X543229D01*
G01X569899Y-285158D02*
X568589Y-284282D01*
X567061Y-283699D01*
X565314D01*
X563349Y-284574D01*
X561821Y-286032D01*
X560729Y-287783D01*
X559856Y-290699D01*
X559637Y-293324D01*
X560074Y-295949D01*
X560729Y-297699D01*
X562039Y-299449D01*
X563568Y-300616D01*
X565096Y-301199D01*
X566624D01*
X568153Y-300616D01*
X569463Y-299741D01*
X570555Y-298575D01*
G01X584342Y-291866D02*
X585216Y-290991D01*
X585871Y-289533D01*
X586308Y-287490D01*
X585871Y-285741D01*
X584998Y-284574D01*
X583469Y-283699D01*
X577574D01*
Y-301199D01*
X584779D01*
X586308Y-300033D01*
X587181Y-298282D01*
X587618Y-296241D01*
X587181Y-294199D01*
X585871Y-292449D01*
X584342Y-291866D01*
X577574D01*
G01X593546Y-307032D02*
X606646D01*
G01X612574Y-301199D02*
Y-283699D01*
X622618Y-301199D01*
Y-283699D01*
G01X635096Y-301199D02*
X633349Y-300907D01*
X631821Y-299741D01*
X630511Y-297991D01*
X629637Y-295949D01*
X629201Y-293616D01*
Y-291282D01*
X629637Y-288949D01*
X630511Y-286907D01*
X631821Y-285158D01*
X633349Y-283991D01*
X635096Y-283699D01*
X636842Y-283991D01*
X638371Y-285158D01*
X639681Y-286907D01*
X640555Y-288949D01*
X640991Y-291282D01*
Y-293616D01*
X640555Y-295949D01*
X639681Y-297991D01*
X638371Y-299741D01*
X636842Y-300907D01*
X635096Y-301199D01*
G01X685937Y-283699D02*
X691396Y-301199D01*
X696855Y-283699D01*
G01X713263Y-301199D02*
X704529D01*
Y-283699D01*
X713263D01*
G01X709769Y-292157D02*
X704529D01*
G01X722029Y-301199D02*
Y-283699D01*
X727488D01*
X729234Y-284574D01*
X730326Y-285741D01*
X730763Y-288074D01*
X730326Y-290408D01*
X729016Y-291866D01*
X727488Y-292741D01*
X722029D01*
G01X727488D02*
X730763Y-301199D01*
G01X743896Y-301782D02*
X743459Y-301491D01*
Y-300907D01*
X743896Y-300616D01*
X744333Y-300907D01*
Y-301491D01*
X743896Y-301782D01*
G01X717646Y-346199D02*
Y-328699D01*
X715026Y-332199D01*
G01Y-346199D02*
X720266D01*
G01X819479Y-283699D02*
Y-301199D01*
X828213D01*
G01X845276D02*
Y-289533D01*
G01Y-291574D02*
X844403Y-290408D01*
X843092Y-289824D01*
X841564Y-289533D01*
X840036Y-290116D01*
X838726Y-291282D01*
X837852Y-293032D01*
X837416Y-295366D01*
X837852Y-297699D01*
X838726Y-299449D01*
X840036Y-300616D01*
X841564Y-301199D01*
X843092Y-300907D01*
X844403Y-300033D01*
X845276Y-298866D01*
G01X854261Y-306449D02*
X855571Y-307032D01*
X857318Y-306449D01*
X858409Y-305283D01*
X859283Y-303824D01*
X860592Y-299158D01*
X863431Y-289533D01*
G01X856444D02*
X860592Y-299158D01*
G01X873071Y-293324D02*
X880058D01*
X879403Y-291282D01*
X878311Y-290116D01*
X876783Y-289533D01*
X875254Y-289824D01*
X873944Y-290699D01*
X873071Y-292741D01*
X872634Y-294491D01*
Y-296241D01*
X873071Y-297991D01*
X874163Y-299741D01*
X875473Y-300907D01*
X877001Y-301199D01*
X878529Y-300616D01*
X880058Y-298866D01*
G01X890789Y-301199D02*
Y-289533D01*
G01Y-291866D02*
X891881Y-290699D01*
X892973Y-289824D01*
X894501Y-289533D01*
X895592Y-289824D01*
X896903Y-290699D01*
G01X871963Y-328699D02*
Y-346199D01*
X863229D01*
G01X850096D02*
X848568Y-345907D01*
X846821Y-345033D01*
X845729Y-343575D01*
X845293Y-341532D01*
X845729Y-339491D01*
X847039Y-337741D01*
X849004Y-336866D01*
X851188D01*
X852498Y-336282D01*
X853590Y-334824D01*
X854026Y-332783D01*
X853371Y-330741D01*
X851843Y-329282D01*
X850096Y-328699D01*
X848350Y-329282D01*
X846821Y-330741D01*
X846166Y-332783D01*
X846603Y-334824D01*
X847694Y-336282D01*
X849004Y-336866D01*
X851188D01*
X853153Y-337741D01*
X854463Y-339491D01*
X854899Y-341532D01*
X854463Y-343575D01*
X853371Y-345033D01*
X851624Y-345907D01*
X850096Y-346199D01*
G01X959846Y-328699D02*
X962902Y-346199D01*
X966396Y-328699D01*
X969889Y-346199D01*
X972946Y-328699D01*
G01X979529Y-346199D02*
Y-328699D01*
X984769D01*
X986516Y-329574D01*
X987826Y-331616D01*
X988263Y-333949D01*
X987826Y-336282D01*
X986734Y-338032D01*
X984769Y-338908D01*
X979529D01*
G01X996811Y-346199D02*
Y-328699D01*
G01X1005981D02*
Y-346199D01*
G01Y-337449D02*
X996811D01*
G01X1016058Y-340366D02*
X1021734D01*
G01X1031593Y-346199D02*
Y-328699D01*
G01X1039889D02*
X1031593Y-339491D01*
G01X1041199Y-346199D02*
X1035304Y-334533D01*
G01X1058263Y-346199D02*
X1049529D01*
Y-328699D01*
X1058263D01*
G01X1054769Y-337157D02*
X1049529D01*
G01X1066374Y-346199D02*
Y-328699D01*
X1076418Y-346199D01*
Y-328699D01*
G01X1083874Y-346199D02*
Y-328699D01*
X1093918Y-346199D01*
Y-328699D01*
G01X961593Y-301199D02*
Y-283699D01*
X965959D01*
X967706Y-284574D01*
X969016Y-285741D01*
X970108Y-287490D01*
X970981Y-289533D01*
X971199Y-292449D01*
X970981Y-295366D01*
X970108Y-297408D01*
X969016Y-299158D01*
X967706Y-300324D01*
X965959Y-301199D01*
X961593D01*
G01X980621Y-293324D02*
X987608D01*
X986953Y-291282D01*
X985861Y-290116D01*
X984333Y-289533D01*
X982804Y-289824D01*
X981494Y-290699D01*
X980621Y-292741D01*
X980184Y-294491D01*
Y-296241D01*
X980621Y-297991D01*
X981713Y-299741D01*
X983023Y-300907D01*
X984551Y-301199D01*
X986079Y-300616D01*
X987608Y-298866D01*
G01X998121Y-299158D02*
X999213Y-300324D01*
X1000741Y-301199D01*
X1002051D01*
X1003361Y-300616D01*
X1004234Y-299741D01*
X1004671Y-298575D01*
X1004453Y-296824D01*
X1003579Y-295949D01*
X999649Y-294199D01*
X998776Y-292157D01*
X999213Y-290699D01*
X1000086Y-289824D01*
X1001396Y-289533D01*
X1002706Y-289824D01*
X1004016Y-290699D01*
G01X1018896Y-289533D02*
Y-301199D01*
G01Y-284866D02*
X1018459Y-284574D01*
Y-283991D01*
X1018896Y-283699D01*
X1019333Y-283991D01*
Y-284574D01*
X1018896Y-284866D01*
G01X1033339Y-305574D02*
X1034868Y-306741D01*
X1036614Y-307032D01*
X1038142Y-306741D01*
X1039453Y-305283D01*
X1040326Y-303241D01*
Y-289533D01*
G01Y-291866D02*
X1039453Y-290699D01*
X1038142Y-289824D01*
X1036614Y-289533D01*
X1034868Y-290116D01*
X1033776Y-291282D01*
X1032902Y-293324D01*
X1032466Y-295366D01*
X1032684Y-297116D01*
X1033558Y-299158D01*
X1034868Y-300616D01*
X1036614Y-301199D01*
X1037924Y-300907D01*
X1039453Y-299741D01*
X1040326Y-298575D01*
G01X1050184Y-301199D02*
Y-289533D01*
G01Y-292449D02*
X1051058Y-290991D01*
X1052368Y-289824D01*
X1054114Y-289533D01*
X1055642Y-289824D01*
X1056953Y-290991D01*
X1057608Y-293032D01*
Y-301199D01*
G01X1068121Y-293324D02*
X1075108D01*
X1074453Y-291282D01*
X1073361Y-290116D01*
X1071833Y-289533D01*
X1070304Y-289824D01*
X1068994Y-290699D01*
X1068121Y-292741D01*
X1067684Y-294491D01*
Y-296241D01*
X1068121Y-297991D01*
X1069213Y-299741D01*
X1070523Y-300907D01*
X1072051Y-301199D01*
X1073579Y-300616D01*
X1075108Y-298866D01*
G01X1085839Y-301199D02*
Y-289533D01*
G01Y-291866D02*
X1086931Y-290699D01*
X1088023Y-289824D01*
X1089551Y-289533D01*
X1090642Y-289824D01*
X1091953Y-290699D01*
G01X1132596Y-346199D02*
Y-328699D01*
X1129976Y-332199D01*
G01Y-346199D02*
X1135216D01*
G01X1150096D02*
Y-328699D01*
X1147476Y-332199D01*
G01Y-346199D02*
X1152716D01*
G01X1163666Y-346782D02*
X1171526Y-328699D01*
G01X1185096Y-346199D02*
Y-328699D01*
X1182476Y-332199D01*
G01Y-346199D02*
X1187716D01*
G01X1198448Y-338908D02*
X1199976Y-336866D01*
X1201286Y-335699D01*
X1203033Y-335116D01*
X1204561Y-335699D01*
X1205653Y-336866D01*
X1206526Y-338616D01*
X1206744Y-340657D01*
X1206526Y-342408D01*
X1205653Y-344158D01*
X1204342Y-345616D01*
X1202814Y-346199D01*
X1201068Y-345616D01*
X1199539Y-343866D01*
X1198666Y-341241D01*
X1198448Y-338324D01*
X1198884Y-334533D01*
X1199539Y-332490D01*
X1200631Y-330449D01*
X1202159Y-328991D01*
X1203688Y-328699D01*
X1205216Y-329282D01*
X1206308Y-330741D01*
G01X1216166Y-346782D02*
X1224026Y-328699D01*
G01X1233448Y-331616D02*
X1234758Y-329866D01*
X1236286Y-328991D01*
X1238033Y-328699D01*
X1240216Y-329282D01*
X1241744Y-330741D01*
X1242181Y-332490D01*
X1241963Y-334241D01*
X1241089Y-335699D01*
X1236723Y-338616D01*
X1234758Y-340657D01*
X1233448Y-343575D01*
X1233011Y-346199D01*
X1242181D01*
G01X1255096Y-328699D02*
X1253349Y-329282D01*
X1252039Y-330741D01*
X1251166Y-332490D01*
X1250511Y-334824D01*
X1250293Y-337449D01*
X1250511Y-340074D01*
X1251166Y-342408D01*
X1252039Y-344158D01*
X1253349Y-345616D01*
X1255096Y-346199D01*
X1256842Y-345616D01*
X1258153Y-344158D01*
X1259026Y-342408D01*
X1259681Y-340074D01*
X1259899Y-337449D01*
X1259681Y-334824D01*
X1259026Y-332490D01*
X1258153Y-330741D01*
X1256842Y-329282D01*
X1255096Y-328699D01*
G01X1272596Y-346199D02*
Y-328699D01*
X1269976Y-332199D01*
G01Y-346199D02*
X1275216D01*
G01X1285948Y-338908D02*
X1287476Y-336866D01*
X1288786Y-335699D01*
X1290533Y-335116D01*
X1292061Y-335699D01*
X1293153Y-336866D01*
X1294026Y-338616D01*
X1294244Y-340657D01*
X1294026Y-342408D01*
X1293153Y-344158D01*
X1291842Y-345616D01*
X1290314Y-346199D01*
X1288568Y-345616D01*
X1287039Y-343866D01*
X1286166Y-341241D01*
X1285948Y-338324D01*
X1286384Y-334533D01*
X1287039Y-332490D01*
X1288131Y-330449D01*
X1289659Y-328991D01*
X1291188Y-328699D01*
X1292716Y-329282D01*
X1293808Y-330741D01*
G01X1180293Y-301199D02*
Y-283699D01*
X1184659D01*
X1186406Y-284574D01*
X1187716Y-285741D01*
X1188808Y-287490D01*
X1189681Y-289533D01*
X1189899Y-292449D01*
X1189681Y-295366D01*
X1188808Y-297408D01*
X1187716Y-299158D01*
X1186406Y-300324D01*
X1184659Y-301199D01*
X1180293D01*
G01X1206526D02*
Y-289533D01*
G01Y-291574D02*
X1205653Y-290408D01*
X1204342Y-289824D01*
X1202814Y-289533D01*
X1201286Y-290116D01*
X1199976Y-291282D01*
X1199102Y-293032D01*
X1198666Y-295366D01*
X1199102Y-297699D01*
X1199976Y-299449D01*
X1201286Y-300616D01*
X1202814Y-301199D01*
X1204342Y-300907D01*
X1205653Y-300033D01*
X1206526Y-298866D01*
G01X1220096Y-283699D02*
Y-301199D01*
G01X1217039Y-289533D02*
X1223153D01*
G01X1234321Y-293324D02*
X1241308D01*
X1240653Y-291282D01*
X1239561Y-290116D01*
X1238033Y-289533D01*
X1236504Y-289824D01*
X1235194Y-290699D01*
X1234321Y-292741D01*
X1233884Y-294491D01*
Y-296241D01*
X1234321Y-297991D01*
X1235413Y-299741D01*
X1236723Y-300907D01*
X1238251Y-301199D01*
X1239779Y-300616D01*
X1241308Y-298866D01*
G01X1031474Y9728D02*
X1025140D01*
X1019641Y4229D01*
Y2164D01*
X1016895Y-582D01*
X1009711D01*
X1008353Y-1940D01*
G01X997007Y49560D02*
Y49939D01*
X996251Y49183D01*
Y45701D01*
G01X1035323Y-758D02*
X1026961D01*
X1026334Y-131D01*
X1019884D01*
X1017815Y-2200D01*
X1012917D01*
X1012177Y-2940D01*
G01X1041813Y2948D02*
X1037837D01*
X1037731Y2842D01*
G01D02*
Y1650D01*
X1035323Y-758D01*
G01X1040140Y7513D02*
X1040748D01*
X1045313Y2948D01*
G01X1019859Y-7642D02*
X1019731Y-7514D01*
Y-3245D01*
X1021644Y-1332D01*
X1025837D01*
X1027563Y-3058D01*
X1042542D01*
X1044391Y-1209D01*
G01X1039767Y14710D02*
Y11386D01*
X1040140Y11013D01*
G01X1025679Y28550D02*
X1028512D01*
X1028912Y28150D01*
X1035181D01*
X1036013Y27318D01*
G01X1039767Y14710D02*
X1037767Y16710D01*
X1037316D01*
X1034826Y19200D01*
X1023800D01*
X1022100Y20900D01*
Y26900D01*
X1023750Y28550D01*
X1025679D01*
G01Y31110D02*
X1028308D01*
X1029381Y32183D01*
X1031240D01*
X1033971Y34914D01*
G01X1036267Y14710D02*
Y11406D01*
X1035830Y10969D01*
G01X1025679Y31110D02*
X1022210D01*
X1020100Y29000D01*
Y19700D01*
X1022600Y17200D01*
X1033777D01*
X1036267Y14710D01*
G01X1031474Y9728D02*
X1033571D01*
X1035830Y7469D01*
G01X1045313Y2948D02*
X1045700Y2561D01*
Y100D01*
X1044391Y-1209D01*
G54D39*
X120351Y630236D03*
X126851D03*
X143217Y501760D03*
X156862Y501811D03*
X152916Y501536D03*
X146960Y501630D03*
X165851Y627736D03*
X137551Y625736D03*
X149851Y627736D03*
X155851D03*
X160851D03*
X217000Y538300D03*
X221000Y529300D03*
X500332Y133764D03*
X493245Y133625D03*
X489680Y133605D03*
X503827Y133704D03*
X563002Y137395D03*
X559591D03*
X597044Y133868D03*
X593636D03*
X600522Y133853D03*
X603924D03*
X635500Y349900D03*
X630500D03*
X627000D03*
X639000D03*
X848660Y789290D03*
X1175156Y138119D03*
X1171622Y139828D03*
X1168207Y139826D03*
X1178558Y138118D03*
X1240709Y150353D03*
X1237308D03*
X1269834Y147434D03*
X1266432D03*
X1289500Y277800D03*
G54D57*
X699900Y269500D03*
X702300D03*
X699900Y266500D03*
X702300D03*
X699900Y263500D03*
X702300D03*
X699900Y260500D03*
X702300D03*
X699900Y257500D03*
X702300D03*
X699900Y251500D03*
X702300D03*
X699900Y272500D03*
X702300D03*
X699900Y254500D03*
X702300D03*
X1219300Y239500D03*
X1221700D03*
X1219300Y242500D03*
X1221700D03*
X1219300Y221500D03*
X1221700D03*
X1219300Y236500D03*
X1221700D03*
X1219300Y233500D03*
X1221700D03*
X1219300Y230500D03*
X1221700D03*
X1219300Y227500D03*
X1221700D03*
X1219300Y224500D03*
X1221700D03*
X1219300Y260500D03*
X1221700D03*
X1219300Y257500D03*
X1221700D03*
X1219300Y266500D03*
X1221700D03*
X1219300Y263500D03*
X1221700D03*
X1219300Y245500D03*
X1221700D03*
X1219300Y248500D03*
X1221700D03*
X1219300Y251500D03*
X1221700D03*
X1219300Y254500D03*
X1221700D03*
G54D66*
X1025679Y31110D03*
Y28550D03*
Y25990D03*
Y23435D03*
X1015079D03*
Y25990D03*
Y28550D03*
Y31110D03*
G54D48*
X285900Y148900D03*
X307300Y780100D03*
X579234Y243270D03*
X626863Y233108D03*
X700800Y817300D03*
X721887Y201942D03*
X1168407Y823010D03*
X1312300Y271400D03*
X1329500Y817400D03*
G54D76*
G01X172309Y476559D02*
X172226Y476642D01*
X172227Y477418D01*
X169155Y480490D01*
Y483250D01*
X170139Y484237D01*
X170140Y484238D01*
X170928D01*
X172065Y485374D01*
G01X172067Y482225D02*
X170928Y483364D01*
X170503D01*
X170029Y482888D01*
Y480853D01*
X172844Y478038D01*
X173624D01*
X173707Y477955D01*
G01X178365Y488524D02*
Y487548D01*
X179977Y485936D01*
Y484499D01*
X181530Y482946D01*
X191181D01*
X193112Y481015D01*
Y480235D01*
X193195Y480152D01*
G01X181514Y485374D02*
Y484274D01*
X181968Y483820D01*
X191545D01*
X193237Y482128D01*
X194013D01*
X195077Y481064D01*
G54D58*
X695763Y278608D03*
Y281008D03*
X692763Y278608D03*
Y281008D03*
X698763Y278608D03*
Y281008D03*
G54D67*
X1039500Y50700D03*
G54D49*
X282300Y143300D03*
X632363Y238108D03*
X652600Y788200D03*
X952200Y44100D03*
X1318700Y266500D03*
X1369100Y254500D03*
G54D77*
G01X137669Y601495D02*
X138038Y601126D01*
Y598861D01*
X141199Y595700D01*
Y587002D01*
X142401Y585800D01*
X145535D01*
X146737Y587002D01*
Y591700D01*
X147237Y592200D01*
X149100D01*
X149600Y591700D01*
Y588002D01*
X152343Y585259D01*
Y584321D01*
X151805Y583783D01*
X148440D01*
X147200Y582543D01*
Y579985D01*
X148440Y578745D01*
X151805D01*
X152343Y578207D01*
Y576645D01*
X151805Y576107D01*
X148440D01*
X147200Y574867D01*
Y572309D01*
X148440Y571069D01*
X151805D01*
X152343Y570531D01*
Y562381D01*
X154030Y560694D01*
Y552360D01*
X152639Y550969D01*
X151339D01*
X150472Y551836D01*
X147451D01*
G01X140818Y601495D02*
X139733D01*
X139238Y601000D01*
Y599359D01*
X142399Y596198D01*
Y587500D01*
X142899Y587000D01*
X145037D01*
X145537Y587500D01*
Y592198D01*
X146739Y593400D01*
X149598D01*
X150800Y592198D01*
Y588500D01*
X153543Y585757D01*
Y583823D01*
X152303Y582583D01*
X148938D01*
X148400Y582045D01*
Y580483D01*
X148938Y579945D01*
X152303D01*
X153543Y578705D01*
Y576147D01*
X152303Y574907D01*
X148938D01*
X148400Y574369D01*
Y572807D01*
X148938Y572269D01*
X152303D01*
X153543Y571029D01*
Y562879D01*
X155230Y561192D01*
Y551862D01*
X153137Y549769D01*
X150841D01*
X149974Y550636D01*
X148551D01*
X147451Y549536D01*
G01X206076Y204850D02*
Y206512D01*
X207481Y207917D01*
Y237722D01*
X219866Y250107D01*
Y289166D01*
X196609Y312423D01*
Y329242D01*
X204900Y337533D01*
Y353400D01*
X251654Y400154D01*
Y401019D01*
X252795Y402161D01*
X253661D01*
X254802Y403302D01*
Y404167D01*
X255943Y405309D01*
X256809D01*
X257950Y406450D01*
Y407315D01*
X259091Y408457D01*
X259957D01*
X261098Y409598D01*
Y410463D01*
X262239Y411605D01*
X263105D01*
X269700Y418200D01*
Y466998D01*
X277630Y474928D01*
Y506182D01*
X275237Y508575D01*
X260363D01*
X259424Y507636D01*
Y503657D01*
X260407Y502674D01*
G01X257207D02*
X258224Y503691D01*
Y508134D01*
X259865Y509775D01*
X275735D01*
X278830Y506680D01*
Y474430D01*
X270900Y466500D01*
Y417702D01*
X206100Y352902D01*
Y337035D01*
X197809Y328744D01*
Y312921D01*
X221066Y289664D01*
Y249609D01*
X208681Y237224D01*
Y207917D01*
X210086Y206512D01*
Y204850D01*
G01X178365Y507422D02*
G03X178688Y507187I912J914D01*
G03X179278Y507044I591J1148D01*
G01X180892D01*
X181504Y507656D01*
X183118D01*
X183730Y507044D01*
X185344D01*
X185956Y507656D01*
X187570D01*
X188182Y507044D01*
X189968D01*
X191876Y508952D01*
Y509817D01*
X193017Y510959D01*
X193883D01*
X195024Y512100D01*
X197555D01*
G03X198494Y512983I0J941D01*
G01Y513944D01*
G02X198774Y514620I956J0D01*
G02X199450Y514900I676J-676D01*
G01X201150D01*
G01Y510900D02*
X195522D01*
X190466Y505844D01*
X178000D01*
G02X175939Y506697I-1J2914D01*
G01X175896Y506741D01*
X175215Y507422D01*
G01X197420Y821701D02*
X197973Y822254D01*
G03X198499Y823526I-1273J1271D01*
G01Y823780D01*
G03X198425Y824154I-982J0D01*
G01X198350Y824337D01*
G03X196778Y825803I-2388J-985D01*
G01X196776D01*
G03X196696Y825829I-1463J-4366D01*
G03X195320Y826040I-1378J-4394D01*
G01X187264D01*
G02X185725Y826968I-1J1739D01*
G02X185300Y828697I3296J1727D01*
G01Y872000D01*
G02X186573Y875073I4346J0D01*
G01X187900Y876400D01*
G03X188645Y877647I-2100J2101D01*
G03X188770Y878500I-2845J853D01*
G01Y882100D01*
X188771Y882101D01*
Y884428D01*
G03X188547Y884969I-765J0D01*
G01X188347Y885169D01*
G02X187796Y886499I1330J1330D01*
G01Y889470D01*
G01X200620Y821701D02*
X200251Y822070D01*
G02X199700Y823400I1330J1330D01*
G01Y823524D01*
G03X199699Y823526I-2683J-1340D01*
G01Y823780D01*
G03X199536Y824610I-2183J2D01*
G01X199460Y824795D01*
G03X197158Y826942I-3498J-1443D01*
G03X197055Y826975I-1206J-3587D01*
G03X195321Y827240I-1734J-5540D01*
G01X187264D01*
G02X186788Y827527I0J538D01*
G02X186500Y828697I2233J1170D01*
G01Y871953D01*
G02X187454Y874256I3257J0D01*
G01X188749Y875551D01*
G03X189795Y877302I-2949J2949D01*
G01X189794D01*
G03X189970Y878499I-3994J1199D01*
G01Y878800D01*
X189971D01*
Y884370D01*
G02X190275Y885104I1038J0D01*
G03X190945Y886722I-1618J1618D01*
G01Y889470D01*
G01X197244D02*
Y884699D01*
G03X197795Y883369I1881J0D01*
G01X197995Y883169D01*
G02X198219Y882628I-541J-541D01*
G01Y880301D01*
X198218Y880300D01*
Y874090D01*
G02X197218Y871676I-3414J0D01*
G01X206297Y188492D02*
X207440Y189635D01*
Y198324D01*
X206076Y199688D01*
Y201350D01*
G01X209866Y188492D02*
X208640Y189718D01*
Y198242D01*
X210086Y199688D01*
Y201350D01*
G01X204650Y514900D02*
X205385Y514166D01*
G03X206827Y513568I1443J1442D01*
G01X208441D01*
G02X210302Y512798I2J-2629D01*
G01X216208Y506892D01*
X218464D01*
X218525Y506831D01*
X220075D01*
X221169Y507925D01*
Y508269D01*
X224669Y511769D01*
X237369D01*
X244899Y519299D01*
X284983D01*
X295846Y508436D01*
Y483562D01*
X290507Y478223D01*
Y468625D01*
X289100Y467218D01*
Y414714D01*
X231682Y357300D01*
X225698D01*
X211917Y343519D01*
Y335726D01*
X203193Y327002D01*
Y316307D01*
X229239Y290261D01*
X245838D01*
X305949Y230150D01*
X342650D01*
X355792Y217008D01*
Y194110D01*
X393988Y155914D01*
Y145012D01*
X422247Y116753D01*
X435045D01*
X455798Y96000D01*
X465287D01*
X500193Y61094D01*
Y29109D01*
X523280Y6022D01*
X700018D01*
X717687Y-11647D01*
X779758D01*
X781543Y-13432D01*
X824469D01*
X825952Y-11949D01*
X895620D01*
X906240Y-1329D01*
Y15637D01*
X910404Y19801D01*
X966201D01*
X966202Y19800D01*
X967928Y21526D01*
Y28246D01*
X970563Y30881D01*
X991002D01*
X1005586Y45465D01*
X1010433D01*
X1016254Y39644D01*
X1020263D01*
X1022419Y37488D01*
X1028442D01*
X1032909Y41955D01*
X1037657D01*
X1044615Y48913D01*
Y63373D01*
X1052094Y70852D01*
X1056348D01*
X1057896Y72400D01*
G01X204650Y510900D02*
X205544Y511794D01*
G02X206930Y512368I1386J-1386D01*
G01X208442D01*
G02X209453Y511949I0J-1429D01*
G01X215710Y505692D01*
X217966D01*
X218027Y505631D01*
X220573D01*
X222369Y507427D01*
Y507771D01*
X225167Y510569D01*
X237867D01*
X245397Y518099D01*
X284485D01*
X294646Y507938D01*
Y484060D01*
X289307Y478721D01*
Y469123D01*
X287900Y467716D01*
Y415212D01*
X231184Y358500D01*
X225200D01*
X210717Y344017D01*
Y336224D01*
X201993Y327500D01*
Y315809D01*
X228741Y289061D01*
X245340D01*
X305451Y228950D01*
X342152D01*
X354592Y216510D01*
Y193612D01*
X392788Y155416D01*
Y144514D01*
X421749Y115553D01*
X434547D01*
X455300Y94800D01*
X464789D01*
X498993Y60596D01*
Y28611D01*
X522782Y4822D01*
X699520D01*
X717189Y-12847D01*
X779260D01*
X781045Y-14632D01*
X824967D01*
X826450Y-13149D01*
X896118D01*
X907440Y-1827D01*
Y15139D01*
X910901Y18600D01*
X966700D01*
X969128Y21028D01*
Y27748D01*
X971061Y29681D01*
X991500D01*
X1006084Y44265D01*
X1009935D01*
X1015756Y38444D01*
X1019765D01*
X1021921Y36288D01*
X1028940D01*
X1033407Y40755D01*
X1038155D01*
X1045815Y48415D01*
Y62875D01*
X1052592Y69652D01*
X1056634D01*
X1057896Y68390D01*
G01X225591Y889470D02*
Y884923D01*
X225590Y884922D01*
G02X224920Y883304I-2288J0D01*
G03X224616Y882570I734J-734D01*
G01Y877588D01*
G03X225615Y875176I3411J0D01*
G01X212992Y889470D02*
Y884922D01*
G02X212322Y883304I-2288J0D01*
G03X212018Y882570I734J-734D01*
G01Y877588D01*
G03X213017Y875176I3411J0D01*
G01X200394Y889470D02*
Y884923D01*
X200393Y884922D01*
G02X199723Y883304I-2288J0D01*
G03X199419Y882570I734J-734D01*
G01Y873000D01*
G03X199649Y872445I785J0D01*
G01X200418Y871676D01*
G01X222441Y889470D02*
Y884699D01*
G03X222992Y883369I1881J0D01*
G01X223192Y883169D01*
G02X223416Y882628I-541J-541D01*
G01Y880301D01*
X223415Y880300D01*
Y877590D01*
G02X222415Y875176I-3414J0D01*
G01X209843Y889470D02*
Y884699D01*
G03X210394Y883369I1881J0D01*
G01X210594Y883169D01*
G02X210818Y882628I-541J-541D01*
G01Y880301D01*
X210817Y880300D01*
Y877590D01*
G02X209817Y875176I-3414J0D01*
G01X260237Y889470D02*
Y884923D01*
X260236Y884922D01*
G02X259566Y883304I-2288J0D01*
G03X259262Y882570I734J-734D01*
G01Y877588D01*
G03X260261Y875176I3411J0D01*
G01X238189Y889470D02*
Y884923D01*
X238188Y884922D01*
G02X237518Y883304I-2288J0D01*
G03X237214Y882570I734J-734D01*
G01Y877588D01*
G03X238213Y875176I3411J0D01*
G01X257087Y889470D02*
Y884699D01*
G03X257638Y883369I1881J0D01*
G01X257838Y883169D01*
G02X258062Y882628I-541J-541D01*
G01Y880301D01*
X258061Y880300D01*
Y877590D01*
G02X257061Y875176I-3414J0D01*
G01X235040Y889470D02*
Y884700D01*
X235039Y884699D01*
G03X235590Y883369I1881J0D01*
G01X235790Y883169D01*
G02X236014Y882628I-541J-541D01*
G01Y880301D01*
X236013Y880300D01*
Y877590D01*
G02X235013Y875176I-3414J0D01*
G01X285433Y889470D02*
Y884922D01*
G02X284763Y883304I-2288J0D01*
G03X284459Y882570I734J-734D01*
G01Y868713D01*
G03X285500Y866200I3554J0D01*
G01X272835Y889470D02*
Y884923D01*
X272834Y884922D01*
G02X272164Y883304I-2288J0D01*
G03X271860Y882570I734J-734D01*
G01Y877588D01*
G03X272859Y875176I3411J0D01*
G01X282284Y889470D02*
Y884699D01*
G03X282835Y883369I1881J0D01*
G01X283035Y883169D01*
G02X283259Y882628I-541J-541D01*
G01Y880301D01*
X283258Y880300D01*
Y868513D01*
G02X282300Y866200I-3271J0D01*
G01X269685Y889470D02*
Y884699D01*
G03X270236Y883369I1881J0D01*
G01X270436Y883169D01*
G02X270660Y882628I-541J-541D01*
G01Y880301D01*
X270659Y880300D01*
Y877590D01*
G02X269659Y875176I-3414J0D01*
G01X323229Y889470D02*
Y884923D01*
X323228Y884922D01*
G02X322558Y883304I-2288J0D01*
G03X322254Y882570I734J-734D01*
G01Y877588D01*
G03X323253Y875176I3411J0D01*
G01X310630Y889470D02*
Y884924D01*
X310631Y884923D01*
X310630Y884922D01*
G02X309960Y883304I-2288J0D01*
G03X309656Y882570I734J-734D01*
G01Y867800D01*
G03X310239Y866391I1992J-1D01*
G01X310955Y865676D01*
G01X332677Y889470D02*
Y884699D01*
G03X333228Y883369I1881J0D01*
G01X333428Y883169D01*
G02X333652Y882628I-541J-541D01*
G01Y880301D01*
X333651Y880300D01*
Y877590D01*
G02X332651Y875176I-3414J0D01*
G01X320079Y889470D02*
Y884699D01*
G03X320630Y883369I1881J0D01*
G01X320830Y883169D01*
G02X321054Y882628I-541J-541D01*
G01Y880301D01*
X321053Y880300D01*
Y877590D01*
G02X320053Y875176I-3414J0D01*
G01X307481Y889470D02*
Y884699D01*
G03X308032Y883369I1881J0D01*
G01X308232Y883169D01*
G02X308456Y882628I-541J-541D01*
G01Y880301D01*
X308455Y880300D01*
Y867366D01*
G02X307755Y865676I-2390J0D01*
G01X361024Y889470D02*
Y884923D01*
X361023Y884922D01*
G02X360353Y883304I-2288J0D01*
G03X360049Y882570I734J-734D01*
G01Y877588D01*
G03X361048Y875176I3411J0D01*
G01X348426Y889470D02*
Y884923D01*
X348425Y884922D01*
G02X347755Y883304I-2288J0D01*
G03X347451Y882570I734J-734D01*
G01Y877588D01*
G03X348450Y875176I3411J0D01*
G01X335827Y889470D02*
Y884923D01*
X335826Y884922D01*
G02X335156Y883304I-2288J0D01*
G03X334852Y882570I734J-734D01*
G01Y877588D01*
G03X335851Y875176I3411J0D01*
G01X357874Y889470D02*
Y884699D01*
G03X358425Y883369I1881J0D01*
G01X358625Y883169D01*
G02X358849Y882628I-541J-541D01*
G01Y880301D01*
X358848Y880300D01*
Y877590D01*
G02X357848Y875176I-3414J0D01*
G01X345276Y889470D02*
Y884699D01*
G03X345827Y883369I1881J0D01*
G01X346027Y883169D01*
G02X346251Y882628I-541J-541D01*
G01Y880301D01*
X346250Y880300D01*
Y877590D01*
G02X345250Y875176I-3414J0D01*
G01X367675Y723000D02*
G03X368500Y724992I-1992J1992D01*
G01Y729416D01*
X370766Y742267D01*
X379909Y755325D01*
X401276Y770287D01*
X433247Y815947D01*
X436307Y833300D01*
Y862623D01*
X436308Y862624D01*
Y865971D01*
G03X436150Y866352I-538J0D01*
G01X434936Y867565D01*
G02X434440Y868767I1204J1200D01*
G01Y881150D01*
X434439Y882100D01*
X434440Y882101D01*
Y884428D01*
G03X434216Y884969I-765J0D01*
G01X434016Y885169D01*
G02X433465Y886499I1330J1330D01*
G01Y889470D01*
G01X436614D02*
Y886722D01*
G02X435944Y885104I-2288J0D01*
G03X435640Y884370I734J-734D01*
G01Y868767D01*
G03X435786Y868414I500J0D01*
G01X437362Y866838D01*
G02X437508Y866485I-354J-353D01*
G01Y862126D01*
X437507Y862125D01*
Y833195D01*
X434383Y815477D01*
X427873Y806179D01*
X428034Y805272D01*
X427108Y803950D01*
X426200Y803790D01*
X425274Y802468D01*
X425435Y801560D01*
X424509Y800238D01*
X423601Y800078D01*
X422675Y798756D01*
X422835Y797848D01*
X421910Y796526D01*
X421002Y796366D01*
X402138Y769425D01*
X380771Y754463D01*
X371902Y741797D01*
X369700Y729311D01*
Y726277D01*
G03Y726255I999J-11D01*
G01Y725837D01*
G03X370875Y723000I4012J0D01*
G01X395670Y889470D02*
Y884923D01*
X395669Y884922D01*
G02X394999Y883304I-2288J0D01*
G03X394695Y882570I734J-734D01*
G01Y877588D01*
G03X395694Y875176I3411J0D01*
G01X383071Y889470D02*
Y884922D01*
G02X382401Y883304I-2288J0D01*
G03X382097Y882570I734J-734D01*
G01Y877588D01*
G03X383096Y875176I3411J0D01*
G01X392520Y889470D02*
Y884699D01*
G03X393071Y883369I1881J0D01*
G01X393271Y883169D01*
G02X393495Y882628I-541J-541D01*
G01Y880301D01*
X393494Y880300D01*
Y877590D01*
G02X392494Y875176I-3414J0D01*
G01X379922Y889470D02*
Y884699D01*
G03X380473Y883369I1881J0D01*
G01X380673Y883169D01*
G02X380897Y882628I-541J-541D01*
G01Y880301D01*
X380896Y880300D01*
Y877590D01*
G02X379896Y875176I-3414J0D01*
G01X420866Y889470D02*
Y884922D01*
G02X420196Y883304I-2288J0D01*
G03X419892Y882570I734J-734D01*
G01Y877588D01*
G03X420891Y875176I3411J0D01*
G01X408268Y889470D02*
Y884923D01*
X408267Y884922D01*
G02X407597Y883304I-2288J0D01*
G03X407293Y882570I734J-734D01*
G01Y877588D01*
G03X408292Y875176I3411J0D01*
G01X417717Y889470D02*
Y884699D01*
G03X418268Y883369I1881J0D01*
G01X418468Y883169D01*
G02X418692Y882628I-541J-541D01*
G01Y880301D01*
X418691Y880300D01*
Y877590D01*
G02X417691Y875176I-3414J0D01*
G01X405118Y889470D02*
Y884699D01*
G03X405669Y883369I1881J0D01*
G01X405869Y883169D01*
G02X406093Y882628I-541J-541D01*
G01Y880301D01*
X406092Y880300D01*
Y877590D01*
G02X405092Y875176I-3414J0D01*
G01X715320Y29700D02*
X714458Y28837D01*
G02X712600Y28068I-1857J1858D01*
G01X707197D01*
G03X704499Y26951I-1J-3815D01*
G01X698499Y20951D01*
G02X694738Y19393I-3761J3761D01*
G01X693124D01*
X692512Y20005D01*
X690898D01*
X690286Y19393D01*
X688672D01*
X688060Y20005D01*
X686446D01*
X685834Y19393D01*
X684220D01*
X683608Y20005D01*
X681994D01*
X681382Y19393D01*
X679768D01*
X679156Y20005D01*
X677542D01*
X676930Y19393D01*
X535596D01*
G02X532115Y20835I0J4923D01*
G01X530974Y21976D01*
Y22842D01*
X529832Y23983D01*
X528967D01*
X527826Y25124D01*
Y25990D01*
X526684Y27131D01*
X525819D01*
X521419Y31531D01*
G02X520581Y33553I2022J2023D01*
G01Y46266D01*
G02X521541Y48584I3279J0D01*
G01X522899Y49942D01*
X525435Y51304D01*
G02X526163Y51085I254J-474D01*
G01X527104Y49331D01*
G01X715380Y25530D02*
G03X712150Y26868I-3230J-3230D01*
G01X707197D01*
G03X705348Y26102I0J-2615D01*
G01X699348Y20102D01*
G02X694738Y18193I-4609J4610D01*
G01X535596D01*
G02X531266Y19986I-1J6123D01*
G01X520570Y30682D01*
G02X519381Y33552I2871J2871D01*
G01Y46266D01*
G02X520692Y49433I4479J1D01*
G01X522175Y50916D01*
X524868Y52362D01*
X524867D01*
X524869Y52363D01*
X524870Y52364D01*
G03X525090Y53092I-254J474D01*
G01X524151Y54843D01*
G01X567323Y889470D02*
Y884922D01*
G02X566653Y883304I-2288J0D01*
G03X566349Y882570I734J-734D01*
G01Y877588D01*
G03X567348Y875176I3411J0D01*
G01X554725Y889470D02*
Y884922D01*
G02X554055Y883304I-2288J0D01*
G03X553751Y882570I734J-734D01*
G01Y877588D01*
G03X554750Y875176I3411J0D01*
G01X542126Y889470D02*
Y884922D01*
G02X541456Y883304I-2288J0D01*
G03X541152Y882570I734J-734D01*
G01Y877588D01*
G03X542151Y875176I3411J0D01*
G01X564174Y889470D02*
Y884699D01*
G03X564725Y883369I1881J0D01*
G01X564925Y883169D01*
G02X565149Y882628I-541J-541D01*
G01Y880301D01*
X565148Y880300D01*
Y877590D01*
G02X564148Y875176I-3414J0D01*
G01X551575Y889470D02*
Y884700D01*
X551576Y884699D01*
G03X552127Y883369I1881J0D01*
G01X552327Y883169D01*
G02X552551Y882628I-541J-541D01*
G01Y880301D01*
X552550Y880300D01*
Y877590D01*
G02X551550Y875176I-3414J0D01*
G01X538977Y889470D02*
Y884699D01*
G03X539528Y883369I1881J0D01*
G01X539728Y883169D01*
G02X539952Y882628I-541J-541D01*
G01Y880301D01*
X539951Y880300D01*
Y877590D01*
G02X538951Y875176I-3414J0D01*
G01X592520Y889470D02*
Y884922D01*
G02X591850Y883304I-2288J0D01*
G03X591546Y882570I734J-734D01*
G01Y877588D01*
G03X592545Y875176I3411J0D01*
G01X579922Y889470D02*
Y884922D01*
G02X579252Y883304I-2288J0D01*
G03X578948Y882570I734J-734D01*
G01Y877588D01*
G03X579947Y875176I3411J0D01*
G01X601969Y889470D02*
Y884700D01*
X601970Y884699D01*
G03X602521Y883369I1881J0D01*
G01X602721Y883169D01*
G02X602945Y882628I-541J-541D01*
G01Y880301D01*
X602944Y880300D01*
Y877590D01*
G02X601944Y875176I-3414J0D01*
G01X589371Y889470D02*
Y884699D01*
G03X589922Y883369I1881J0D01*
G01X590122Y883169D01*
G02X590346Y882628I-541J-541D01*
G01Y880301D01*
X590345Y880300D01*
Y877590D01*
G02X589345Y875176I-3414J0D01*
G01X576772Y889470D02*
Y884700D01*
X576773Y884699D01*
G03X577324Y883369I1881J0D01*
G01X577524Y883169D01*
G02X577748Y882628I-541J-541D01*
G01Y880301D01*
X577747Y880300D01*
Y877590D01*
G02X576747Y875176I-3414J0D01*
G01X715080Y53200D02*
X713440Y51560D01*
X710684D01*
G03X708676Y50729I-1J-2840D01*
G01X707535Y49588D01*
X706669D01*
X705528Y48446D01*
Y47581D01*
X704387Y46440D01*
X703521D01*
X702380Y45298D01*
Y44433D01*
X701239Y43292D01*
X700373D01*
X699232Y42150D01*
Y41285D01*
X698091Y40144D01*
X697225D01*
X696084Y39002D01*
Y38137D01*
X684383Y26436D01*
G02X681561Y25267I-2822J2822D01*
G01X614555D01*
G02X612364Y26175I1J3099D01*
G01X609221Y29318D01*
G02X608521Y31008I1690J1690D01*
G01Y39324D01*
X609133Y39936D01*
Y41550D01*
X608521Y42162D01*
Y43776D01*
X609133Y44388D01*
Y46002D01*
X608521Y46614D01*
Y48228D01*
G02X608955Y49276I1482J0D01*
G01X609755Y50076D01*
X612049Y51302D01*
X612052Y51304D01*
G02X612780Y51084I254J-474D01*
G01X613718Y49331D01*
G01X715080Y49100D02*
X713820Y50360D01*
X710684D01*
G03X709525Y49880I0J-1639D01*
G01X685232Y25587D01*
G02X681561Y24067I-3670J3671D01*
G01X614554D01*
G02X611515Y25326I1J4299D01*
G01X608372Y28469D01*
G02X607321Y31008I2539J2538D01*
G01Y48228D01*
G02X608106Y50125I2683J1D01*
G01X609032Y51051D01*
X611483Y52361D01*
Y52362D01*
G03X611704Y53091I-253J475D01*
G01X610766Y54843D01*
G01X630315Y889470D02*
Y884922D01*
G02X629645Y883304I-2288J0D01*
G03X629341Y882570I734J-734D01*
G01Y877588D01*
G03X630340Y875176I3411J0D01*
G01X617717Y889470D02*
Y884922D01*
G02X617047Y883304I-2288J0D01*
G03X616743Y882570I734J-734D01*
G01Y876400D01*
G03X616902Y876016I543J0D01*
G01X617742Y875176D01*
G01X605119Y889470D02*
Y884922D01*
G02X604449Y883304I-2288J0D01*
G03X604145Y882570I734J-734D01*
G01Y877588D01*
G03X605144Y875176I3411J0D01*
G01X627166Y889470D02*
Y884699D01*
G03X627717Y883369I1881J0D01*
G01X627917Y883169D01*
G02X628141Y882628I-541J-541D01*
G01Y880301D01*
X628140Y880300D01*
Y877590D01*
G02X627140Y875176I-3414J0D01*
G01X614567Y889470D02*
Y884700D01*
X614568Y884699D01*
G03X615119Y883369I1881J0D01*
G01X615319Y883169D01*
G02X615543Y882628I-541J-541D01*
G01Y880301D01*
X615542Y880300D01*
Y877590D01*
G02X614542Y875176I-3414J0D01*
G01X664961Y889470D02*
Y884922D01*
G02X664291Y883304I-2288J0D01*
G03X663987Y882570I734J-734D01*
G01Y877588D01*
G03X664986Y875176I3411J0D01*
G01X652363Y889470D02*
Y884922D01*
G02X651693Y883304I-2288J0D01*
G03X651389Y882570I734J-734D01*
G01Y877588D01*
G03X652388Y875176I3411J0D01*
G01X661811Y889470D02*
Y884700D01*
X661812Y884699D01*
G03X662363Y883369I1881J0D01*
G01X662563Y883169D01*
G02X662787Y882628I-541J-541D01*
G01Y880301D01*
X662786Y880300D01*
Y877590D01*
G02X661786Y875176I-3414J0D01*
G01X649213Y889470D02*
Y884700D01*
X649214Y884699D01*
G03X649765Y883369I1881J0D01*
G01X649965Y883169D01*
G02X650189Y882628I-541J-541D01*
G01Y880301D01*
X650188Y880300D01*
Y877590D01*
G02X649188Y875176I-3414J0D01*
G01X702756Y889470D02*
Y884922D01*
G02X702086Y883304I-2288J0D01*
G03X701782Y882570I734J-734D01*
G01Y870292D01*
G03X702400Y868800I2110J0D01*
G01X690158Y889470D02*
Y884922D01*
G02X689488Y883304I-2288J0D01*
G03X689184Y882570I734J-734D01*
G01Y877588D01*
G03X690183Y875176I3411J0D01*
G01X677560Y889470D02*
Y884922D01*
G02X676890Y883304I-2288J0D01*
G03X676586Y882570I734J-734D01*
G01Y877588D01*
G03X677585Y875176I3411J0D01*
G01X699607Y889470D02*
Y884699D01*
G03X700158Y883369I1881J0D01*
G01X700358Y883169D01*
G02X700582Y882628I-541J-541D01*
G01Y880301D01*
X700581Y880300D01*
Y871178D01*
G02X699876Y869476I-2407J0D01*
G01X699200Y868800D01*
G01X687008Y889470D02*
Y884700D01*
X687009Y884699D01*
G03X687560Y883369I1881J0D01*
G01X687760Y883169D01*
G02X687984Y882628I-541J-541D01*
G01Y880301D01*
X687983Y880300D01*
Y877590D01*
G02X686983Y875176I-3414J0D01*
G01X674410Y889470D02*
Y884700D01*
X674411Y884699D01*
G03X674962Y883369I1881J0D01*
G01X675162Y883169D01*
G02X675386Y882628I-541J-541D01*
G01Y880301D01*
X675385Y880300D01*
Y877590D01*
G02X674385Y875176I-3414J0D01*
G01X722955Y33095D02*
X723955Y32095D01*
Y31327D01*
G02X723225Y29563I-2493J-1D01*
G01X722891Y29229D01*
G02X721109Y28259I-2532J2530D01*
G02X718820Y29700I0J2539D01*
G01X726155Y33095D02*
X725155Y32095D01*
Y31327D01*
X725156D01*
G02X724074Y28714I-3694J-1D01*
G01X723740Y28380D01*
G02X721359Y27085I-3381J3380D01*
G03X718840Y25490I0J-2787D01*
G01X718580Y53200D02*
X720038Y51743D01*
G03X720744Y51450I707J706D01*
G02X722251Y50826I0J-2132D01*
G01X723402Y49676D01*
X724314Y48764D01*
Y48763D01*
X724653Y48424D01*
G03X725071Y48251I418J418D01*
G01X725609D01*
X726609Y49251D01*
G01Y46051D02*
X725609Y47051D01*
X725071D01*
G02X723804Y47575I-1J1792D01*
G01X721402Y49977D01*
G03X720743Y50249I-658J-660D01*
G01X720126D01*
G03X719449Y49968I1J-958D01*
G01X718580Y49100D01*
G01X734252Y889470D02*
Y884922D01*
G02X733582Y883304I-2288J0D01*
G03X733278Y882570I734J-734D01*
G01Y877588D01*
G03X734277Y875176I3411J0D01*
G01X731103Y889470D02*
Y884699D01*
G03X731654Y883369I1881J0D01*
G01X731854Y883169D01*
G02X732078Y882628I-541J-541D01*
G01Y880301D01*
X732077Y880300D01*
Y877590D01*
G02X731077Y875176I-3414J0D01*
G01X772048Y889470D02*
Y884922D01*
G02X771378Y883304I-2288J0D01*
G03X771074Y882570I734J-734D01*
G01Y877588D01*
G03X772073Y875176I3411J0D01*
G01X759449Y889470D02*
Y884922D01*
G02X758779Y883304I-2288J0D01*
G03X758475Y882570I734J-734D01*
G01Y877588D01*
G03X759474Y875176I3411J0D01*
G01X746851Y889470D02*
Y884922D01*
G02X746181Y883304I-2288J0D01*
G03X745877Y882570I734J-734D01*
G01Y877588D01*
G03X746876Y875176I3411J0D01*
G01X768898Y889470D02*
Y884700D01*
X768899Y884699D01*
G03X769450Y883369I1881J0D01*
G01X769650Y883169D01*
G02X769874Y882628I-541J-541D01*
G01Y880301D01*
X769873Y880300D01*
Y877590D01*
G02X768873Y875176I-3414J0D01*
G01X756300Y889470D02*
Y884699D01*
G03X756851Y883369I1881J0D01*
G01X757051Y883169D01*
G02X757275Y882628I-541J-541D01*
G01Y880301D01*
X757274Y880300D01*
Y877590D01*
G02X756274Y875176I-3414J0D01*
G01X743701Y889470D02*
Y884700D01*
X743702Y884699D01*
G03X744253Y883369I1881J0D01*
G01X744453Y883169D01*
G02X744677Y882628I-541J-541D01*
G01Y880301D01*
X744676Y880300D01*
Y877590D01*
G02X743676Y875176I-3414J0D01*
G01X830050Y176200D02*
G03X828279Y177350I-1771J-789D01*
G01X826580D01*
X811946Y181979D01*
X811739Y182187D01*
X809272Y183913D01*
X801989Y189012D01*
X801150Y189851D01*
X801131Y189871D01*
X801051Y189951D01*
G02X800000Y192490I2539J2538D01*
G01Y193587D01*
G03X799000Y196000I-3414J-1D01*
G01X802200D02*
G03X801200Y193586I2414J-2414D01*
G01Y192490D01*
G03X801900Y190800I2390J0D01*
G01X802764Y189936D01*
X807168Y186853D01*
X809961Y184897D01*
X812474Y183139D01*
G02X812548Y183076I-310J-439D01*
G01X812588Y183036D01*
X826766Y178550D01*
X828279D01*
G03X830050Y179700I0J1939D01*
G01X797245Y889470D02*
Y884922D01*
G02X796575Y883304I-2288J0D01*
G03X796271Y882570I734J-734D01*
G01Y877588D01*
G03X797270Y875176I3411J0D01*
G01X784646Y889470D02*
Y884922D01*
G02X783976Y883304I-2288J0D01*
G03X783672Y882570I734J-734D01*
G01Y877588D01*
G03X784671Y875176I3411J0D01*
G01X794095Y889470D02*
Y884700D01*
X794096Y884699D01*
G03X794647Y883369I1881J0D01*
G01X794847Y883169D01*
G02X795071Y882628I-541J-541D01*
G01Y880301D01*
X795070Y880300D01*
Y877590D01*
G02X794070Y875176I-3414J0D01*
G01X781497Y889470D02*
Y884699D01*
G03X782048Y883369I1881J0D01*
G01X782248Y883169D01*
G02X782472Y882628I-541J-541D01*
G01Y880301D01*
X782471Y880300D01*
Y877590D01*
G02X781471Y875176I-3414J0D01*
G01X833550Y176200D02*
G02X836447Y177400I2897J-2897D01*
G01X838352D01*
G02X838988Y177178I-1J-1024D01*
G02X839076Y177100I-634J-804D01*
G03X840324Y176387I1931J1931D01*
G03X841007Y176300I684J2644D01*
G01X878907D01*
G01Y177500D02*
X841009D01*
G02X840624Y177549I-1J1533D01*
G02X839924Y177950I384J1482D01*
G03X839734Y178118I-1566J-1580D01*
G01X839735Y178119D01*
G03X838353Y178600I-1381J-1743D01*
G01X836206D01*
G02X833550Y179700I0J3756D01*
G01X835040Y889470D02*
Y884922D01*
G02X834370Y883304I-2288J0D01*
G03X834066Y882570I734J-734D01*
G01Y877588D01*
G03X835065Y875176I3411J0D01*
G01X809843Y889470D02*
Y884922D01*
G02X809173Y883304I-2288J0D01*
G03X808869Y882570I734J-734D01*
G01Y877588D01*
G03X809868Y875176I3411J0D01*
G01X831890Y889470D02*
Y884700D01*
X831891Y884699D01*
G03X832442Y883369I1881J0D01*
G01X832642Y883169D01*
G02X832866Y882628I-541J-541D01*
G01Y880301D01*
X832865Y880300D01*
Y877590D01*
G02X831865Y875176I-3414J0D01*
G01X806693Y889470D02*
Y884700D01*
X806694Y884699D01*
G03X807245Y883369I1881J0D01*
G01X807445Y883169D01*
G02X807669Y882628I-541J-541D01*
G01Y880301D01*
X807668Y880300D01*
Y877590D01*
G02X806668Y875176I-3414J0D01*
G01X847638Y889470D02*
Y884922D01*
G02X846968Y883304I-2288J0D01*
G03X846664Y882570I734J-734D01*
G01Y877588D01*
G03X847663Y875176I3411J0D01*
G01X844489Y889470D02*
Y884699D01*
G03X845040Y883369I1881J0D01*
G01X845240Y883169D01*
G02X845464Y882628I-541J-541D01*
G01Y880301D01*
X845463Y880300D01*
Y877590D01*
G02X844463Y875176I-3414J0D01*
G01X931500Y144600D02*
X932566D01*
X933465Y143701D01*
G01X931500Y146800D02*
X932627D01*
X933465Y147638D01*
G01X939400Y144500D02*
X938201D01*
X937402Y143701D01*
G01X939400Y146700D02*
X938340D01*
X937402Y147638D01*
G01X927600Y142700D02*
X928527D01*
X929528Y143701D01*
G01X927600Y144900D02*
Y145710D01*
X929528Y147638D01*
G01X943400Y144700D02*
X942338D01*
X941339Y143701D01*
G01X943400Y146900D02*
X942077D01*
X941339Y147638D01*
G01X951200Y144800D02*
X950311D01*
X949212Y143701D01*
G01X951200Y147000D02*
X949850D01*
X949212Y147638D01*
G01X1038189Y889470D02*
Y884922D01*
G02X1037519Y883304I-2288J0D01*
G03X1037215Y882570I734J-734D01*
G01Y877588D01*
G03X1038214Y875176I3411J0D01*
G01X1035040Y889470D02*
Y884699D01*
G03X1035591Y883369I1881J0D01*
G01X1035791Y883169D01*
G02X1036015Y882628I-541J-541D01*
G01Y880301D01*
X1036014Y880300D01*
Y877590D01*
G02X1035014Y875176I-3414J0D01*
G01X1065700Y32888D02*
X1066700Y33888D01*
X1068362D01*
X1069750Y32500D01*
G01X1065700Y36088D02*
X1066700Y35088D01*
X1068338D01*
X1069750Y36500D01*
G01X1061200Y20888D02*
X1062200Y21888D01*
X1063862D01*
X1065250Y20500D01*
G01X1061200Y24088D02*
X1062200Y23088D01*
X1063838D01*
X1065250Y24500D01*
G01X1129466Y49331D02*
G03X1125781Y49431I-1890J-1695D01*
G01X1111603Y35253D01*
G02X1108986Y34169I-2617J2616D01*
G01X1088743D01*
G03X1087910Y33823I2J-1180D01*
G01X1087909D01*
G02X1085378Y32774I-2532J2532D01*
G01X1081856D01*
G02X1079641Y33691I-1J3132D01*
G03X1079124Y33906I-518J-516D01*
G01X1074656D01*
X1073250Y32500D01*
G01Y36500D02*
X1074644Y35106D01*
X1079124D01*
G02X1080490Y34540I0J-1931D01*
G03X1081856Y33974I1366J1365D01*
G01X1085377D01*
G03X1087060Y34672I-1J2381D01*
G01X1087061Y34673D01*
G02X1088743Y35369I1682J-1684D01*
G01X1108985D01*
G03X1110753Y36101I0J2500D01*
G01X1125400Y50748D01*
G03X1126513Y54843I-3019J3019D01*
G01X1216080Y49331D02*
G03X1212661Y49872I-1906J-972D01*
G01X1211372Y48583D01*
G03X1210507Y46495I2088J-2088D01*
G01Y33045D01*
G02X1209423Y30428I-3700J0D01*
G01X1200298Y21303D01*
G02X1197681Y20219I-2617J2616D01*
G01X1080889D01*
G02X1077952Y21435I-1J4153D01*
G03X1076711Y21950I-1242J-1240D01*
G01X1070200D01*
X1068750Y20500D01*
G01Y24500D02*
X1070100Y23150D01*
X1076711D01*
G02X1078801Y22284I0J-2955D01*
G03X1080889Y21419I2088J2088D01*
G01X1197680D01*
G03X1199448Y22151I0J2500D01*
G01X1208575Y31278D01*
G03X1209307Y33046I-1768J1768D01*
G01Y46495D01*
G02X1210523Y49432I4153J1D01*
G01X1213326Y52235D01*
G03X1213128Y54843I-1219J1219D01*
G01X1126513Y99725D02*
G02X1125000Y96788I-1513J-1079D01*
G01X1119972D01*
X1119360Y97400D01*
X1117746D01*
X1117134Y96788D01*
X1115520D01*
X1114908Y97400D01*
X1113294D01*
X1112682Y96788D01*
X1104600D01*
X1078834Y71022D01*
X1064436D01*
X1063058Y72400D01*
X1061396D01*
G01X1129466Y94213D02*
G03X1127133Y95588I-2333J-1292D01*
G01X1105098D01*
X1079332Y69822D01*
X1064436D01*
X1063058Y68444D01*
X1061342D01*
G01X1075985Y889470D02*
Y884922D01*
G02X1075315Y883304I-2288J0D01*
G03X1075011Y882570I734J-734D01*
G01Y877588D01*
G03X1076010Y875176I3411J0D01*
G01X1050788Y889470D02*
Y884922D01*
G02X1050118Y883304I-2288J0D01*
G03X1049814Y882570I734J-734D01*
G01Y877588D01*
G03X1050813Y875176I3411J0D01*
G01X1072835Y889470D02*
Y884700D01*
X1072836Y884699D01*
G03X1073387Y883369I1881J0D01*
G01X1073587Y883169D01*
G02X1073811Y882628I-541J-541D01*
G01Y880301D01*
X1073810Y880300D01*
Y877590D01*
G02X1072810Y875176I-3414J0D01*
G01X1047638Y889470D02*
Y884700D01*
X1047639Y884699D01*
G03X1048190Y883369I1881J0D01*
G01X1048390Y883169D01*
G02X1048614Y882628I-541J-541D01*
G01Y880301D01*
X1048613Y880300D01*
Y877590D01*
G02X1047613Y875176I-3414J0D01*
G01X1147183Y49331D02*
Y57451D01*
G03X1146324Y59525I-2934J0D01*
G01X1146232Y59617D01*
G03X1144100Y60500I-2132J-2132D01*
G01X1124396D01*
G02X1122935Y61105I0J2066D01*
G01X1112005Y72035D01*
X1111902Y72087D01*
X1111379Y72435D01*
X1110653Y72735D01*
X1109611Y72943D01*
X1105610D01*
G02X1103300Y73900I0J3267D01*
G01X1144230Y54843D02*
X1145485Y56098D01*
G03X1145983Y57300I-1202J1202D01*
G01Y57450D01*
G03X1145475Y58676I-1734J0D01*
G01X1145382Y58769D01*
G03X1144100Y59300I-1282J-1282D01*
G01X1124396D01*
G02X1122086Y60256I-1J3266D01*
G01X1111292Y71050D01*
X1110811Y71370D01*
X1110302Y71581D01*
X1109492Y71743D01*
X1105700D01*
G03X1103467Y70818I0J-3158D01*
G01X1103349Y70700D01*
G01X1101182Y889470D02*
Y884922D01*
G02X1100512Y883304I-2288J0D01*
G03X1100208Y882570I734J-734D01*
G01Y877588D01*
G03X1101207Y875176I3411J0D01*
G01X1088583Y889470D02*
Y884922D01*
G02X1087913Y883304I-2288J0D01*
G03X1087609Y882570I734J-734D01*
G01Y877588D01*
G03X1088608Y875176I3411J0D01*
G01X1098032Y889470D02*
Y884700D01*
X1098033Y884699D01*
G03X1098584Y883369I1881J0D01*
G01X1098784Y883169D01*
G02X1099008Y882628I-541J-541D01*
G01Y880301D01*
X1099007Y880300D01*
Y877590D01*
G02X1098007Y875176I-3414J0D01*
G01X1085434Y889470D02*
Y884699D01*
G03X1085985Y883369I1881J0D01*
G01X1086185Y883169D01*
G02X1086409Y882628I-541J-541D01*
G01Y880301D01*
X1086408Y880300D01*
Y877590D01*
G02X1085408Y875176I-3414J0D01*
G01X1112700Y80700D02*
G03X1112114Y82566I-3264J0D01*
G01X1110635Y84045D01*
X1110623Y84058D01*
G02X1109800Y86144I2230J2085D01*
G01Y86600D01*
G02X1113500Y90300I3700J0D01*
G01X1149399D01*
X1149400Y90301D01*
G02X1151788Y89311I-1J-3378D01*
G01X1158096Y83004D01*
G02X1159201Y81333I-3540J-3542D01*
G01X1162409Y73369D01*
G03X1163473Y71322I11102J4471D01*
G01X1168134Y64146D01*
G03X1169275Y63005I3256J2115D01*
G01X1171811Y61357D01*
G03X1173501Y60657I2731J4204D01*
G01X1180165Y59241D01*
G02X1182155Y56783I-523J-2458D01*
G01Y55228D01*
G02X1182123Y54549I-7110J-5D01*
G02X1182001Y53752I-7078J676D01*
G03X1181631Y50216I16708J-3536D01*
G01Y49331D01*
G01X1178679Y54843D02*
X1178334Y53224D01*
G03X1179210Y51875I1112J-237D01*
G01X1179211D01*
G03X1180560Y52750I237J1112D01*
G01X1180826Y54002D01*
G03X1180927Y54663I-5782J1222D01*
G03X1180954Y55227I-5882J564D01*
G01X1180955D01*
Y56783D01*
G03X1179915Y58067I-1313J0D01*
G01X1173252Y59483D01*
G02X1171157Y60350I1289J6078D01*
G01X1168621Y61998D01*
G02X1167127Y63492I2769J4263D01*
G01X1162466Y70668D01*
G02X1161295Y72920I11044J7173D01*
G01X1158087Y80884D01*
G03X1157247Y82155I-3532J-1421D01*
G01X1150939Y88462D01*
G03X1149464Y89100I-1541J-1539D01*
G01X1113500D01*
G03X1111000Y86600I0J-2500D01*
G01Y86144D01*
G03X1111500Y84878I1853J0D01*
G01X1112869Y83509D01*
G03X1114842Y83078I1973J4300D01*
G01X1138977Y889470D02*
Y884922D01*
G02X1138307Y883304I-2288J0D01*
G03X1138003Y882570I734J-734D01*
G01Y877588D01*
G03X1139002Y875176I3411J0D01*
G01X1126378Y889470D02*
Y884922D01*
G02X1125708Y883304I-2288J0D01*
G03X1125404Y882570I734J-734D01*
G01Y877588D01*
G03X1126403Y875176I3411J0D01*
G01X1113780Y889470D02*
Y884922D01*
G02X1113110Y883304I-2288J0D01*
G03X1112806Y882570I734J-734D01*
G01Y877588D01*
G03X1113805Y875176I3411J0D01*
G01X1135827Y889470D02*
Y884700D01*
X1135828Y884699D01*
G03X1136379Y883369I1881J0D01*
G01X1136579Y883169D01*
G02X1136803Y882628I-541J-541D01*
G01Y880301D01*
X1136802Y880300D01*
Y877590D01*
G02X1135802Y875176I-3414J0D01*
G01X1123229Y889470D02*
Y884699D01*
G03X1123780Y883369I1881J0D01*
G01X1123980Y883169D01*
G02X1124204Y882628I-541J-541D01*
G01Y880301D01*
X1124203Y880300D01*
Y877590D01*
G02X1123203Y875176I-3414J0D01*
G01X1110630Y889470D02*
Y884700D01*
X1110631Y884699D01*
G03X1111182Y883369I1881J0D01*
G01X1111382Y883169D01*
G02X1111606Y882628I-541J-541D01*
G01Y880301D01*
X1111605Y880300D01*
Y877590D01*
G02X1110605Y875176I-3414J0D01*
G01X1164174Y889470D02*
Y884922D01*
G02X1163504Y883304I-2288J0D01*
G03X1163200Y882570I734J-734D01*
G01Y877588D01*
G03X1164199Y875176I3411J0D01*
G01X1151575Y889470D02*
Y884922D01*
G02X1150905Y883304I-2288J0D01*
G03X1150601Y882570I734J-734D01*
G01Y877588D01*
G03X1151600Y875176I3411J0D01*
G01X1161024Y889470D02*
Y884700D01*
X1161025Y884699D01*
G03X1161576Y883369I1881J0D01*
G01X1161776Y883169D01*
G02X1162000Y882628I-541J-541D01*
G01Y880301D01*
X1161999Y880300D01*
Y877590D01*
G02X1160999Y875176I-3414J0D01*
G01X1148426Y889470D02*
Y884699D01*
G03X1148977Y883369I1881J0D01*
G01X1149177Y883169D01*
G02X1149401Y882628I-541J-541D01*
G01Y880301D01*
X1149400Y880300D01*
Y877590D01*
G02X1148400Y875176I-3414J0D01*
G01X1198819Y889470D02*
Y884922D01*
G02X1198149Y883304I-2288J0D01*
G03X1197845Y882570I734J-734D01*
G01Y869400D01*
G03X1199000Y867200I2673J0D01*
G01X1186221Y889470D02*
Y884922D01*
G02X1185551Y883304I-2288J0D01*
G03X1185247Y882570I734J-734D01*
G01Y877588D01*
G03X1186246Y875176I3411J0D01*
G01X1195670Y889470D02*
Y884699D01*
G03X1196221Y883369I1881J0D01*
G01X1196421Y883169D01*
G02X1196645Y882628I-541J-541D01*
G01Y869400D01*
G02X1195800Y867300I-3032J0D01*
G01X1183071Y889470D02*
Y884700D01*
X1183072Y884699D01*
G03X1183623Y883369I1881J0D01*
G01X1183823Y883169D01*
G02X1184047Y882628I-541J-541D01*
G01Y880301D01*
X1184046Y880300D01*
Y877590D01*
G02X1183046Y875176I-3414J0D01*
G01X1242914Y889470D02*
Y884922D01*
G02X1242244Y883304I-2288J0D01*
G03X1241940Y882570I734J-734D01*
G01Y877588D01*
G03X1242939Y875176I3411J0D01*
G01X1230315Y889470D02*
Y884922D01*
G02X1229645Y883304I-2288J0D01*
G03X1229341Y882570I734J-734D01*
G01Y877588D01*
G03X1230340Y875176I3411J0D01*
G01X1239764Y889470D02*
Y884700D01*
X1239765Y884699D01*
G03X1240316Y883369I1881J0D01*
G01X1240516Y883169D01*
G02X1240740Y882628I-541J-541D01*
G01Y880301D01*
X1240739Y880300D01*
Y877590D01*
G02X1239739Y875176I-3414J0D01*
G01X1227166Y889470D02*
Y884699D01*
G03X1227717Y883369I1881J0D01*
G01X1227917Y883169D01*
G02X1228141Y882628I-541J-541D01*
G01Y880301D01*
X1228140Y880300D01*
Y877590D01*
G02X1227140Y875176I-3414J0D01*
G01X1268111Y889470D02*
Y884922D01*
G02X1267441Y883304I-2288J0D01*
G03X1267137Y882570I734J-734D01*
G01Y877588D01*
G03X1268136Y875176I3411J0D01*
G01X1255512Y889470D02*
Y884922D01*
G02X1254842Y883304I-2288J0D01*
G03X1254538Y882570I734J-734D01*
G01Y877588D01*
G03X1255537Y875176I3411J0D01*
G01X1277560Y889470D02*
Y884699D01*
G03X1278111Y883369I1881J0D01*
G01X1278311Y883169D01*
G02X1278535Y882628I-541J-541D01*
G01Y880301D01*
X1278534Y880300D01*
Y877590D01*
G02X1277534Y875176I-3414J0D01*
G01X1264961Y889470D02*
Y884700D01*
X1264962Y884699D01*
G03X1265513Y883369I1881J0D01*
G01X1265713Y883169D01*
G02X1265937Y882628I-541J-541D01*
G01Y880301D01*
X1265936Y880300D01*
Y877590D01*
G02X1264936Y875176I-3414J0D01*
G01X1252363Y889470D02*
Y884699D01*
G03X1252914Y883369I1881J0D01*
G01X1253114Y883169D01*
G02X1253338Y882628I-541J-541D01*
G01Y880301D01*
X1253337Y880300D01*
Y877590D01*
G02X1252337Y875176I-3414J0D01*
G01X1305906Y889470D02*
Y884922D01*
G02X1305236Y883304I-2288J0D01*
G03X1304932Y882570I734J-734D01*
G01Y877588D01*
G03X1305931Y875176I3411J0D01*
G01X1293308Y889470D02*
Y884922D01*
G02X1292638Y883304I-2288J0D01*
G03X1292334Y882570I734J-734D01*
G01Y877588D01*
G03X1293333Y875176I3411J0D01*
G01X1280709Y889470D02*
Y884922D01*
G02X1280039Y883304I-2288J0D01*
G03X1279735Y882570I734J-734D01*
G01Y877588D01*
G03X1280734Y875176I3411J0D01*
G01X1302756Y889470D02*
Y884700D01*
X1302757Y884699D01*
G03X1303308Y883369I1881J0D01*
G01X1303508Y883169D01*
G02X1303732Y882628I-541J-541D01*
G01Y880301D01*
X1303731Y880300D01*
Y877590D01*
G02X1302731Y875176I-3414J0D01*
G01X1290158Y889470D02*
Y884700D01*
X1290159Y884699D01*
G03X1290710Y883369I1881J0D01*
G01X1290910Y883169D01*
G02X1291134Y882628I-541J-541D01*
G01Y880301D01*
X1291133Y880300D01*
Y877590D01*
G02X1290133Y875176I-3414J0D01*
G01X1343701Y889470D02*
Y884922D01*
G02X1343031Y883304I-2288J0D01*
G03X1342727Y882570I734J-734D01*
G01Y877588D01*
G03X1343726Y875176I3411J0D01*
G01X1331103Y889470D02*
Y884922D01*
G02X1330433Y883304I-2288J0D01*
G03X1330129Y882570I734J-734D01*
G01Y877588D01*
G03X1331128Y875176I3411J0D01*
G01X1318504Y889470D02*
Y884922D01*
G02X1317834Y883304I-2288J0D01*
G03X1317530Y882570I734J-734D01*
G01Y877588D01*
G03X1318529Y875176I3411J0D01*
G01X1340552Y889470D02*
Y884699D01*
G03X1341103Y883369I1881J0D01*
G01X1341303Y883169D01*
G02X1341527Y882628I-541J-541D01*
G01Y880301D01*
X1341526Y880300D01*
Y877590D01*
G02X1340526Y875176I-3414J0D01*
G01X1327953Y889470D02*
Y884700D01*
X1327954Y884699D01*
G03X1328505Y883369I1881J0D01*
G01X1328705Y883169D01*
G02X1328929Y882628I-541J-541D01*
G01Y880301D01*
X1328928Y880300D01*
Y877590D01*
G02X1327928Y875176I-3414J0D01*
G01X1315355Y889470D02*
Y884699D01*
G03X1315906Y883369I1881J0D01*
G01X1316106Y883169D01*
G02X1316330Y882628I-541J-541D01*
G01Y880301D01*
X1316329Y880300D01*
Y877590D01*
G02X1315329Y875176I-3414J0D01*
G54D68*
X1039500Y56300D03*
G54D59*
X856650Y16200D03*
X864150Y20075D03*
Y12325D03*
G54D78*
G01X896000Y686000D02*
Y724500D01*
X894500Y726000D01*
X504948D01*
X468272Y689324D01*
X356944D01*
X356943Y689325D01*
X335976D01*
X313701Y667050D01*
X210966D01*
X210965Y667051D01*
X209785D01*
X209784Y667052D01*
X208604D01*
X208602Y667050D01*
X208565D01*
X206552Y665037D01*
X142059D01*
X137446Y669650D01*
X61918D01*
X61917Y669649D01*
X58373D01*
X58372Y669650D01*
X56741D01*
X55991Y670400D01*
X48700D01*
X47300Y669000D01*
X42000D01*
X40000Y671000D01*
X26300D01*
X26100Y671200D01*
G01X241521Y654021D02*
X239174Y651674D01*
X180826D01*
X176500Y656000D01*
X139000D01*
X135000Y660000D01*
X25000D01*
X24000Y659000D01*
G01X257728Y722272D02*
X266575Y713425D01*
X307659D01*
X312855Y708229D01*
Y697807D01*
X294923Y679875D01*
X216285D01*
X216284Y679876D01*
X215104D01*
X215103Y679877D01*
X200829D01*
X200827Y679875D01*
X185331D01*
X182481Y682725D01*
X163272D01*
X157547Y677000D01*
X103500D01*
X100438Y680062D01*
X33062D01*
X29500Y676500D01*
G01X67400Y275100D02*
X61644D01*
X60872Y274328D01*
G01X61870Y515670D02*
X61850Y515650D01*
Y510749D01*
X56602Y505501D01*
X56600D01*
Y505287D01*
X48302Y496989D01*
Y496202D01*
X42700Y490600D01*
Y455127D01*
X66527Y431300D01*
Y373592D01*
X67002Y373117D01*
X67003D01*
X79200Y360920D01*
Y357429D01*
X79455Y357174D01*
G01X35709Y426942D02*
X36651Y426000D01*
X41250D01*
G01X54903Y447003D02*
X67952Y433954D01*
Y390391D01*
X93487Y364856D01*
Y314471D01*
X91000Y311984D01*
Y299400D01*
X94323Y296077D01*
X105108D01*
X110802Y301771D01*
X116255D01*
X129811Y315327D01*
Y327538D01*
X135873Y333600D01*
X160669D01*
X165500Y328769D01*
Y309310D01*
X162300Y306110D01*
Y257999D01*
X165162Y255137D01*
Y166241D01*
X213460Y117943D01*
X213485D01*
X216758Y114670D01*
Y114645D01*
X221262Y110141D01*
Y109790D01*
X221418Y109634D01*
G01X46500Y460300D02*
X58054D01*
X67796Y470042D01*
G01X46087Y455819D02*
X54903Y447003D01*
G01X66854Y507824D02*
X61524D01*
X60150Y506450D01*
G01X50140Y490750D02*
X51978Y492588D01*
Y494128D01*
X53600Y495750D01*
G01X50140Y490750D02*
X50190Y490700D01*
X53700D01*
X54664Y491664D01*
X61564D01*
X64303Y488925D01*
X69720D01*
X72095Y491300D01*
X77353D01*
X78567Y490086D01*
G01X57700Y495750D02*
X60272D01*
X60900Y495122D01*
G01D02*
X65122Y490900D01*
X68901D01*
X71276Y493275D01*
X77756D01*
X78567Y494086D01*
G01X66850Y526900D02*
X61350Y532400D01*
Y532850D01*
X60300Y533900D01*
G01X63000Y558930D02*
X69208Y565138D01*
X80097D01*
X80572Y564663D01*
Y562789D01*
G01X43600Y665700D02*
X45025Y664275D01*
X136773D01*
X140286Y660762D01*
X208325D01*
X209763Y662200D01*
X828752D01*
X887215Y603737D01*
X1269336D01*
X1318845Y653246D01*
Y664761D01*
X1317768Y665838D01*
X1298233D01*
X1289590Y674481D01*
Y730561D01*
X1293867Y734838D01*
X1298500D01*
G01X54200Y666800D02*
X57190D01*
X57191Y666799D01*
X63099D01*
X63100Y666800D01*
X136264D01*
X140877Y662187D01*
X207734D01*
X209747Y664200D01*
X209784D01*
X289605Y664199D01*
X290785D01*
X290786Y664198D01*
X301422D01*
X301424Y664200D01*
X830300D01*
X880889Y613611D01*
G01X47800Y666400D02*
X50190Y668790D01*
X55450D01*
X56015Y668225D01*
X57781D01*
X57782Y668224D01*
X62508D01*
X62509Y668225D01*
X136855D01*
X141468Y663612D01*
X207143D01*
X209156Y665625D01*
X209193D01*
X209194Y665626D01*
X210374D01*
X210375Y665625D01*
X833375D01*
X875252Y623748D01*
G01X35766Y673178D02*
X36298Y673710D01*
X40258D01*
X40718Y673250D01*
X58600D01*
X59350Y672500D01*
X59554D01*
X59555Y672499D01*
X60735D01*
X60736Y672500D01*
X138628D01*
X140703Y670425D01*
X187327D01*
X188440Y669312D01*
X204779D01*
X206792Y671325D01*
X206829D01*
X206831Y671327D01*
X211557D01*
X211558Y671326D01*
X212738D01*
X212739Y671325D01*
X311928D01*
X341591Y700988D01*
X356280D01*
X360818Y696450D01*
X465034D01*
X515533Y746949D01*
X778949D01*
X808584Y776584D01*
G01X1295714Y716714D02*
X1292929Y713929D01*
Y675174D01*
X1299415Y668688D01*
X1318950D01*
X1321695Y665943D01*
Y650195D01*
X1272387Y600887D01*
X886033D01*
X827570Y659350D01*
X210945D01*
X209507Y657912D01*
X139104D01*
X135591Y661425D01*
X39575D01*
X34500Y666500D01*
G01X39900Y678100D02*
X41900Y676100D01*
X67521D01*
X68046Y675575D01*
X139585D01*
X140747Y674413D01*
X187371D01*
X189622Y672162D01*
X203597D01*
X205610Y674175D01*
X205647D01*
X205649Y674177D01*
X212739D01*
X212740Y674176D01*
X213920D01*
X213921Y674175D01*
X297315D01*
X326000Y702860D01*
Y706000D01*
X328331Y708331D01*
G01X33600Y675800D02*
X40184D01*
X41309Y674675D01*
X59395D01*
X60145Y673925D01*
X139219D01*
X141294Y671850D01*
X187918D01*
X189031Y670737D01*
X204188D01*
X206201Y672750D01*
X206238D01*
X206240Y672752D01*
X212148D01*
X212149Y672751D01*
X213329D01*
X213330Y672750D01*
X311337D01*
X341000Y702413D01*
X356871D01*
X361409Y697875D01*
X464443D01*
X514943Y748375D01*
X775659D01*
X799459Y772175D01*
G01X43100Y670900D02*
X44025Y671825D01*
X56582D01*
X57332Y671075D01*
X58963D01*
X58964Y671074D01*
X61326D01*
X61327Y671075D01*
X138037D01*
X142650Y666462D01*
X205961D01*
X207974Y668475D01*
X208011D01*
X208013Y668477D01*
X210375D01*
X210376Y668476D01*
X211556D01*
X211557Y668475D01*
X313110D01*
X342773Y698138D01*
X355098D01*
X359636Y693600D01*
X360320D01*
X360321Y693599D01*
X374545D01*
X374546Y693600D01*
X466500D01*
X514900Y742000D01*
X784000D01*
X816750Y774750D01*
X831500D01*
G01X36624Y669155D02*
X42929Y662850D01*
X136182D01*
X139695Y659337D01*
X208916D01*
X210354Y660775D01*
X828161D01*
X886624Y602312D01*
X1269927D01*
X1320270Y652655D01*
Y665352D01*
X1318359Y667263D01*
X1298824D01*
X1291504Y674583D01*
Y718004D01*
X1294662Y721162D01*
X1319226D01*
X1320500Y719888D01*
G01X214649Y802351D02*
X223075Y793925D01*
Y694591D01*
X216911Y688427D01*
X197605D01*
X193994Y692038D01*
X166506D01*
X158768Y684300D01*
X104000D01*
X101300Y687000D01*
X47700D01*
X45800Y685100D01*
G01X42100Y684000D02*
X43075Y683025D01*
X48100D01*
X50650Y685575D01*
X98957D01*
X104682Y679850D01*
X156365D01*
X162090Y685575D01*
X162091D01*
X167129Y690613D01*
X193403D01*
X197014Y687002D01*
X217502D01*
X224500Y694000D01*
Y796000D01*
X212841Y807659D01*
G01X38000Y684000D02*
X40400Y681600D01*
X49300D01*
X51850Y684150D01*
X98366D01*
X104091Y678425D01*
X156956D01*
X162681Y684150D01*
X168444D01*
X172057Y687763D01*
X192221D01*
X195834Y684150D01*
X199054D01*
X199056Y684152D01*
X216876D01*
X216877Y684151D01*
X218057D01*
X218058Y684150D01*
X293150D01*
X308580Y699580D01*
Y706420D01*
X308244Y706756D01*
Y706792D01*
X307167Y707869D01*
X258631D01*
X254212Y712288D01*
G01X67400Y275100D02*
X72100D01*
G01X92907Y280765D02*
X92829D01*
X92250Y280186D01*
Y273940D01*
G01D02*
X94038D01*
X99167Y268811D01*
X101463D01*
G01X72708Y382055D02*
X74008Y380755D01*
Y380583D01*
X91858Y362733D01*
Y314858D01*
X89300Y312300D01*
Y298926D01*
X93438Y294788D01*
Y293462D01*
X95297Y291603D01*
Y288623D01*
X96304Y287616D01*
G01X100500Y285300D02*
X98620D01*
X96304Y287616D01*
G01X96798Y301484D02*
X94810Y303472D01*
Y311307D01*
X97072Y313569D01*
Y370472D01*
X100417Y373817D01*
Y395258D01*
X122054Y416895D01*
Y432539D01*
X128978Y439463D01*
X140558D01*
X141421Y440326D01*
Y440327D01*
X143927Y442833D01*
Y445667D01*
X143912Y445682D01*
Y450476D01*
X144214Y450778D01*
X144201Y450791D01*
X146150Y452740D01*
G01X96798Y297915D02*
X93335Y301378D01*
Y311961D01*
X95565Y314191D01*
Y369847D01*
X95564Y369848D01*
Y371096D01*
X98942Y374474D01*
Y395869D01*
X99040Y395967D01*
Y396057D01*
X119702Y416719D01*
Y432363D01*
X128277Y440938D01*
X139946D01*
X142452Y443444D01*
Y445056D01*
X142437Y445071D01*
Y450469D01*
X140500Y452406D01*
Y452740D01*
G01X101950Y275460D02*
X105200Y278710D01*
Y284300D01*
X95700Y293800D01*
Y293900D01*
G01X84700Y396000D02*
X85100D01*
X99086Y409986D01*
Y415883D01*
X105776Y422573D01*
Y424486D01*
X114818Y433528D01*
G01X80592Y463549D02*
Y443594D01*
X85042Y439144D01*
G01X96750Y472400D02*
X97287D01*
X104100Y479213D01*
X105144D01*
X114881Y488950D01*
X117867D01*
G01X80950Y478600D02*
X80900Y478650D01*
Y481000D01*
X87875Y487975D01*
X102713D01*
X112068Y497330D01*
X121030D01*
X121673Y497973D01*
G01X93250Y476400D02*
X89550Y472800D01*
X70554D01*
X67796Y470042D01*
G01X73232Y476912D02*
X74782Y475362D01*
X81213D01*
X85414Y479563D01*
X86363D01*
G01X84092Y463549D02*
X89048D01*
X93811Y468312D01*
X96259D01*
X111647Y483700D01*
X114000D01*
G01X96750Y476400D02*
X98250D01*
X104969Y483119D01*
X105555D01*
G01X82067Y490086D02*
X83074Y491093D01*
X92835D01*
X93828Y492086D01*
X95742D01*
G01D02*
X102726D01*
X111988Y501348D01*
Y502242D01*
X113795Y504049D01*
G01X95742Y492086D02*
Y490870D01*
G01X82067Y494086D02*
X83085Y493068D01*
X86787D01*
G01D02*
X92016D01*
X93009Y494061D01*
X101907D01*
X110013Y502167D01*
Y503061D01*
X111937Y504985D01*
G01X86787Y493068D02*
Y494553D01*
G01X96750Y480400D02*
X99401D01*
X105401Y486400D01*
X107863D01*
X115622Y494159D01*
X121010D01*
X121673Y494822D01*
G01X73858Y506552D02*
Y505167D01*
X70910Y502219D01*
G01X70358Y506552D02*
X69086Y507824D01*
X66854D01*
G01X95437Y496084D02*
X101667D01*
X105141Y499558D01*
Y499588D01*
X113500Y507947D01*
X126111D01*
X126358Y507700D01*
X128100D01*
G01X100063Y498972D02*
X98951Y500084D01*
X95437D01*
G01Y504084D02*
X102388D01*
X103055Y503417D01*
G01X130200Y517000D02*
X128459Y515259D01*
X127671D01*
X126380Y516550D01*
X103604D01*
X98768Y511714D01*
Y511687D01*
X98727Y511646D01*
X98294D01*
X97860Y511212D01*
X87538D01*
X84250Y514500D01*
G01X106818Y513350D02*
X100638Y507170D01*
X98294D01*
X97481Y507983D01*
X85733D01*
X84250Y506500D01*
G01Y510500D02*
X85342Y509408D01*
X99221D01*
G01X84250Y502500D02*
Y502717D01*
X88091Y506558D01*
X96890D01*
X97703Y505745D01*
X104071D01*
X106037Y507711D01*
G01X70750Y498500D02*
X70800Y498450D01*
Y496662D01*
X70750Y496612D01*
Y496550D01*
X68600Y494400D01*
G01D02*
X67700Y495300D01*
Y499120D01*
G01X93250Y484600D02*
X89900D01*
X88400Y483100D01*
Y481600D01*
X86363Y479563D01*
G01X96750Y484600D02*
X97650Y485500D01*
X102026D01*
X104498Y487972D01*
X105949D01*
X106900Y488923D01*
G01X80750Y530500D02*
X79417Y529167D01*
X69117D01*
X66850Y526900D01*
G01X88565Y532410D02*
X86655Y530500D01*
X84250D01*
G01X88565Y532410D02*
X88792Y532637D01*
X109776D01*
X114484Y527929D01*
X126433D01*
X127973Y529469D01*
G01X124823Y523170D02*
X123285Y521632D01*
X121036D01*
X119526Y523142D01*
X107996D01*
X106972Y524166D01*
X100010D01*
X98242Y522398D01*
X84352D01*
X84250Y522500D01*
G01X80750D02*
X77700D01*
G01X84250Y546500D02*
X85925D01*
X88278Y548853D01*
G01X102075Y529701D02*
X97351D01*
X96786Y530266D01*
G01X106575Y518876D02*
X106119Y519332D01*
X103962D01*
X98197Y513567D01*
X96009D01*
G01X107341Y528856D02*
X105337D01*
X103610Y527129D01*
X97649D01*
X96786Y526266D01*
G01X96009Y517567D02*
X99032D01*
X99768Y518303D01*
G01X84250Y518500D02*
Y518541D01*
X86668Y520959D01*
X98819D01*
X100601Y522741D01*
X107159D01*
X109014Y520886D01*
X113757D01*
G01X105136Y535172D02*
X105105Y535141D01*
X84891D01*
X84250Y534500D01*
G01X77300Y531238D02*
Y532600D01*
X79200Y534500D01*
X80750D01*
G01X84250Y538500D02*
X84922Y537828D01*
X107943D01*
X111585Y534186D01*
X113380D01*
X113900Y533666D01*
G01X80750Y538500D02*
X77700D01*
G01X95870Y541681D02*
X93992Y539803D01*
X86947D01*
X84250Y542500D01*
G01X102326Y540322D02*
X97229D01*
X95870Y541681D01*
G01X74301Y538390D02*
X74991D01*
X77126Y540525D01*
X82275D01*
X84250Y542500D01*
G01X70515Y538726D02*
X72172Y540383D01*
X74190D01*
X76307Y542500D01*
X80750D01*
G01X65800Y538900D02*
X67638D01*
X67812Y538726D01*
X70515D01*
G01X100270Y545196D02*
X99785Y545681D01*
X95870D01*
G01X74300Y533600D02*
X72900Y535000D01*
X70750D01*
G01X68567Y531405D02*
X69705Y532543D01*
X69756D01*
X70750Y533537D01*
Y535000D01*
G01X73900Y527050D02*
X74250Y526700D01*
Y522500D01*
G01X74050Y545700D02*
X74850Y546500D01*
X80750D01*
G01X74050Y545700D02*
X73700Y545350D01*
Y542600D01*
G01X127973Y523170D02*
X126435Y524708D01*
X109835D01*
X108895Y525648D01*
X99476D01*
X97753Y523925D01*
X89675D01*
X88700Y524900D01*
G01X80750Y554500D02*
X77500D01*
G01X88278Y548853D02*
X89717Y550292D01*
X89856D01*
X92001Y552437D01*
Y552492D01*
X102229D01*
X105926Y548795D01*
Y547851D01*
X114484Y539293D01*
X115971D01*
X121036Y534228D01*
X123212D01*
X124823Y532617D01*
G01X92360Y563260D02*
X98529Y557091D01*
X104073D01*
X113689Y547475D01*
X115988D01*
X116439Y547024D01*
G01X100350Y550196D02*
X100341Y550187D01*
Y550160D01*
X99864Y549683D01*
X95872D01*
X95870Y549681D01*
G01X84250Y550500D02*
X84841Y551091D01*
X88500D01*
X89126Y551717D01*
X89265D01*
X90576Y553028D01*
Y553167D01*
X91650Y554241D01*
X102559D01*
X115100Y541700D01*
G01X65381Y548719D02*
X69762Y553100D01*
X73100D01*
G01D02*
X75750D01*
X76500Y552350D01*
X79250D01*
X80750Y550850D01*
Y550500D01*
G01X80572Y562789D02*
Y558780D01*
X80712Y558640D01*
G01X84072Y562789D02*
Y561952D01*
X85720Y560304D01*
Y560151D01*
X86797Y559074D01*
X86950D01*
X87608Y558416D01*
Y557685D01*
G01X84250Y554500D02*
Y558602D01*
X84212Y558640D01*
G01X121673Y538916D02*
X116489Y544100D01*
X114716D01*
X103150Y555666D01*
X90049D01*
X88338Y553955D01*
G01X84250Y554500D02*
X84716Y554034D01*
X88322D01*
Y553955D01*
X88338D01*
G01X95400Y731600D02*
X95963Y731037D01*
X99700D01*
G01X103800Y729062D02*
X96262D01*
X95400Y728200D01*
G01X72900Y729550D02*
X76400D01*
X76650Y729300D01*
G01X72900Y729550D02*
X69350D01*
X68900Y730000D01*
G01X76650Y733300D02*
X73150D01*
X72900Y733050D01*
G01D02*
X71644D01*
X68465Y736229D01*
G01X85800Y727500D02*
X81950D01*
X80150Y729300D01*
G01Y733300D02*
X83500D01*
X85800Y731000D01*
G01X102499Y281183D02*
X99055D01*
X98588Y281650D01*
G01X134800Y329600D02*
Y328615D01*
X131236Y325051D01*
Y314736D01*
X116846Y300346D01*
X111393D01*
X105500Y294453D01*
Y291250D01*
G01X120700Y282400D02*
X117750D01*
X116906Y283244D01*
G01X110000Y287750D02*
X105500D01*
G01X114350Y288100D02*
X114000Y287750D01*
X110000D01*
G01X116906Y283244D02*
X115200Y284950D01*
Y287250D01*
X114350Y288100D01*
G01X113915Y307600D02*
X114400Y308085D01*
Y316299D01*
X132493Y334392D01*
Y410385D01*
X155727Y433619D01*
Y439395D01*
X152388Y442734D01*
Y450502D01*
X150150Y452740D01*
G01X155680Y452680D02*
X153863Y450863D01*
Y443435D01*
X157234Y440064D01*
Y432994D01*
X134000Y409760D01*
Y335439D01*
X133968Y335407D01*
Y333781D01*
X116234Y316047D01*
Y308850D01*
X117484Y307600D01*
G01X102457Y347690D02*
Y347243D01*
X113000Y336700D01*
Y336000D01*
G01X111000Y324200D02*
X115938Y329138D01*
Y356938D01*
X119650Y360650D01*
Y374390D01*
X125700Y380440D01*
Y383284D01*
X125718Y383302D01*
G01X107558Y321012D02*
X110746Y324200D01*
X111000D01*
G01X124290Y401910D02*
Y398290D01*
X113000Y387000D01*
Y359506D01*
X102457Y348963D01*
Y347690D01*
G01X126122Y432323D02*
X128426Y434627D01*
X132204D01*
G01X114818Y433528D02*
Y434218D01*
X125363Y444763D01*
X130633D01*
G01X131122Y491674D02*
X129510Y490062D01*
X127336D01*
X126435Y489161D01*
Y487961D01*
X103500Y465026D01*
G01D02*
Y461250D01*
G01X128280Y476120D02*
X134272Y482112D01*
Y485374D01*
G01X124822Y488523D02*
Y488342D01*
X108102Y471628D01*
X105728D01*
G01X127142Y470680D02*
Y459404D01*
G01D02*
Y452958D01*
X127820Y452280D01*
G01X98400Y454400D02*
X99900Y452900D01*
X102683D01*
X102733Y452850D01*
X104267D01*
X104317Y452900D01*
X105200D01*
X106900Y454600D01*
Y457000D01*
X107889Y457989D01*
G01D02*
X108650Y458750D01*
X113000D01*
G01Y462250D02*
Y471300D01*
X116204Y474504D01*
G01D02*
X127074Y485374D01*
X127973D01*
G01X130642Y470680D02*
X132110Y472148D01*
Y476134D01*
X133589Y477613D01*
G01X121673Y491672D02*
X118951Y488950D01*
X117867D01*
G01X127973Y510571D02*
X128418Y510126D01*
Y508018D01*
X128100Y507700D01*
G01X100063Y498972D02*
X102539D01*
X112600Y509033D01*
X123285D01*
X124823Y510571D01*
G01X103055Y503417D02*
X105504D01*
X112658Y510571D01*
X121673D01*
G01X127971Y513721D02*
X126094Y515598D01*
X105552D01*
X99362Y509408D01*
X99221D01*
G01X106037Y507711D02*
X110509Y512183D01*
X123283D01*
X124821Y513721D01*
G01X136272Y496478D02*
X134275Y498475D01*
Y499075D01*
X133856Y499494D01*
Y499568D01*
X132524Y500900D01*
X129926D01*
X128610Y499584D01*
X126361D01*
X124823Y501122D01*
G01X117771Y499896D02*
X118997Y501122D01*
X121673D01*
G01X128450Y481470D02*
X130304D01*
X132734Y483900D01*
Y486986D01*
X134272Y488524D01*
G01X131718Y498682D02*
X128682D01*
X127973Y497973D01*
G01X106900Y488923D02*
X114337Y496360D01*
X121018D01*
X121030Y496372D01*
X123222D01*
X124823Y497973D01*
G01X114000Y483700D02*
X116400D01*
X124374Y491674D01*
X124823D01*
G01X105555Y483119D02*
X106752D01*
X116917Y493284D01*
X123285D01*
X124823Y494822D01*
G01X137600Y501338D02*
X136638Y502300D01*
X129200D01*
X128022Y501122D01*
X127973D01*
G01X125070Y598347D02*
X125063Y598340D01*
Y584200D01*
X124673Y583810D01*
X122310D01*
X121974Y583474D01*
Y582200D01*
X122375Y581799D01*
X127802D01*
X129884Y579716D01*
Y578884D01*
X129403Y578403D01*
X128697D01*
X127200Y579899D01*
X122700D01*
X122200Y579399D01*
Y578548D01*
X122848Y577900D01*
X124563D01*
X125100Y577363D01*
Y575284D01*
X125000Y575184D01*
Y573588D01*
X125988Y572600D01*
X130809D01*
X131309Y572100D01*
Y539702D01*
X133705Y537306D01*
X135883D01*
X137421Y535768D01*
G01X121922Y610945D02*
X121549Y610572D01*
Y593850D01*
X120311Y592612D01*
Y589111D01*
X119124Y587924D01*
Y574523D01*
X128459Y565188D01*
Y544728D01*
X126435Y542704D01*
Y531981D01*
X127336Y531080D01*
X132500D01*
X133000Y530580D01*
Y529500D01*
X133500Y529000D01*
X136921D01*
X137421Y529500D01*
Y532618D01*
G01X125070Y614095D02*
Y615330D01*
X124695Y615705D01*
X120800D01*
X120343Y615248D01*
Y612995D01*
X120800Y612538D01*
X122862D01*
X123532Y611868D01*
Y587632D01*
X120549Y584649D01*
Y578196D01*
X120775Y577970D01*
Y577957D01*
X122257Y576475D01*
X122270D01*
X123532Y575213D01*
Y573016D01*
X129884Y566664D01*
Y534700D01*
X130384Y534200D01*
X133772D01*
X134272Y534700D01*
Y535768D01*
G01X116439Y547024D02*
X117363Y546100D01*
X120788D01*
X121673Y545215D01*
G01X131121Y529467D02*
X128405Y526751D01*
X112955D01*
X108494Y531212D01*
X103586D01*
X102075Y529701D01*
G01X130200Y517000D02*
X131121Y517921D01*
Y520018D01*
G01X127971D02*
X125560Y517607D01*
X107844D01*
X106575Y518876D01*
G01X121673Y513721D02*
X107189D01*
X106818Y513350D01*
G01X131121Y523168D02*
X128706Y525583D01*
X111016D01*
X107743Y528856D01*
X107341D01*
G01X124822Y520019D02*
X123285Y518482D01*
X110018D01*
X107388Y521112D01*
X102544D01*
X99768Y518336D01*
Y518303D01*
G01X113757Y520886D02*
X118954D01*
X120073Y519767D01*
X121673D01*
Y520020D01*
G01X115374Y529467D02*
X114249D01*
X108544Y535172D01*
X105136D01*
G01X113900Y533666D02*
X114566Y533000D01*
X114991D01*
X118524Y529467D01*
G01X121673D02*
X121233D01*
X114800Y535900D01*
X112418D01*
X107996Y540322D01*
X102326D01*
G01X100270Y545196D02*
X100273Y545199D01*
X105495D01*
X113894Y536800D01*
X115315D01*
X121036Y531079D01*
X123211D01*
X124823Y529467D01*
G01X100350Y550196D02*
Y550159D01*
X101821D01*
X113980Y538000D01*
X115956D01*
X121339Y532617D01*
X121673D01*
G01X115100Y541700D02*
X116988Y539812D01*
X117468D01*
X121514Y535766D01*
X121673D01*
G01X125072Y610945D02*
Y600520D01*
X126608Y598984D01*
Y585009D01*
X131309Y580308D01*
Y575209D01*
X130486Y574386D01*
X126801D01*
G01X118773Y601495D02*
X117161Y599883D01*
X114783D01*
X111999Y597099D01*
Y564000D01*
X112499Y563500D01*
X117000D01*
X117500Y563000D01*
Y562200D01*
X117000Y561700D01*
X112600D01*
X112100Y561200D01*
Y560138D01*
X112600Y559638D01*
X124900D01*
G01X115622Y614094D02*
X106299Y604771D01*
Y556701D01*
X111300Y551700D01*
X116600D01*
X118190Y550110D01*
X124847D01*
G01X115622Y601496D02*
X114200D01*
X110574Y597870D01*
Y559648D01*
X111922Y558300D01*
X120172D01*
X122010Y556462D01*
X124900D01*
G01X118773Y604645D02*
X120311Y603107D01*
Y594561D01*
X119408Y593658D01*
X118208D01*
X116274Y591724D01*
Y573341D01*
X121009Y568606D01*
Y566708D01*
X121727Y565990D01*
X124900D01*
G01X118773Y598345D02*
X117845D01*
X114849Y595349D01*
Y569692D01*
X116037Y568504D01*
X116709D01*
X117566Y569361D01*
X118238D01*
X118910Y568689D01*
Y568017D01*
X118053Y567160D01*
Y566488D01*
X121727Y562814D01*
X124900D01*
G01X118805Y614099D02*
X114571Y609865D01*
Y609193D01*
X115278Y608486D01*
Y607778D01*
X114642Y607142D01*
X113934D01*
X113227Y607849D01*
X112555D01*
X110790Y606084D01*
Y605412D01*
X112065Y604137D01*
Y603465D01*
X111393Y602793D01*
X110721D01*
X109446Y604068D01*
X108774D01*
X107724Y603018D01*
Y557416D01*
X111854Y553286D01*
X118006D01*
X118481Y552811D01*
Y552075D01*
X118956Y551600D01*
X119906D01*
X120381Y552075D01*
Y552811D01*
X120856Y553286D01*
X124900D01*
G01X115623Y598345D02*
X113424Y596146D01*
Y569101D01*
X121249Y561276D01*
X122547D01*
G01X118773Y610945D02*
X117000D01*
X116500Y610445D01*
Y609000D01*
X117000Y608500D01*
X120000D01*
X120500Y608000D01*
Y606700D01*
X120000Y606200D01*
X114114D01*
X113614Y605700D01*
Y603165D01*
X109149Y598700D01*
Y558575D01*
X111024Y556700D01*
X114982D01*
X115482Y556200D01*
Y555399D01*
X115957Y554924D01*
X116907D01*
X117382Y555399D01*
Y556200D01*
X117882Y556700D01*
X118782D01*
X119282Y556200D01*
Y555399D01*
X119757Y554924D01*
X122547D01*
G01X118773Y589748D02*
X117699Y588674D01*
Y573932D01*
X122434Y569197D01*
Y567741D01*
X122547Y567628D01*
G01X131370Y601496D02*
X131700Y601166D01*
Y592588D01*
X134988Y589300D01*
Y584957D01*
X139145Y580800D01*
Y543790D01*
X137421Y542066D01*
G01X126646Y606400D02*
Y600184D01*
X128033Y598797D01*
Y585600D01*
X132734Y580899D01*
Y540452D01*
X134270Y538916D01*
G01X128220Y614095D02*
X126683Y612558D01*
Y609117D01*
X128184Y607616D01*
Y600316D01*
X129458Y599042D01*
Y586455D01*
X136295Y579618D01*
Y576297D01*
X135820Y575822D01*
X134875D01*
X134400Y575347D01*
Y574397D01*
X134875Y573922D01*
X135820D01*
X136295Y573447D01*
Y572497D01*
X135820Y572022D01*
X134875D01*
X134400Y571547D01*
Y570597D01*
X134875Y570122D01*
X135820D01*
X136295Y569647D01*
Y568697D01*
X135820Y568222D01*
X134875D01*
X134400Y567747D01*
Y566797D01*
X134875Y566322D01*
X135820D01*
X136295Y565847D01*
Y564897D01*
X135820Y564422D01*
X134875D01*
X134400Y563947D01*
Y562997D01*
X134875Y562522D01*
X135820D01*
X136295Y562047D01*
Y561097D01*
X135820Y560622D01*
X134875D01*
X134400Y560147D01*
Y559197D01*
X134875Y558722D01*
X135820D01*
X136295Y558247D01*
Y557297D01*
X135820Y556822D01*
X134875D01*
X134400Y556347D01*
Y555397D01*
X134875Y554922D01*
X135820D01*
X136295Y554447D01*
Y553497D01*
X135820Y553022D01*
X134875D01*
X134400Y552547D01*
Y551597D01*
X134875Y551122D01*
X135820D01*
X136295Y550647D01*
Y549697D01*
X135820Y549222D01*
X134875D01*
X134400Y548747D01*
Y547797D01*
X134875Y547322D01*
X135820D01*
X136295Y546847D01*
Y545972D01*
X134272Y543949D01*
Y542066D01*
G01X131369Y614095D02*
X129759Y612485D01*
Y610380D01*
X132983Y607156D01*
Y593321D01*
X136413Y589891D01*
Y585548D01*
X140570Y581391D01*
Y564143D01*
X141045Y563668D01*
X145900D01*
X146400Y563168D01*
Y562268D01*
X145900Y561768D01*
X141045D01*
X140570Y561293D01*
Y560343D01*
X141045Y559868D01*
X143325D01*
X143800Y559393D01*
Y558443D01*
X143325Y557968D01*
X141045D01*
X140570Y557493D01*
Y535767D01*
G01X128221Y610945D02*
Y609679D01*
X129832Y608068D01*
Y600859D01*
X130600Y600091D01*
Y591842D01*
X133563Y588879D01*
Y584366D01*
X137720Y580209D01*
Y544737D01*
X135883Y542900D01*
Y540456D01*
X137421Y538918D01*
G01X122167Y730758D02*
Y731990D01*
G01X111850Y731900D02*
X112992Y730758D01*
X122167D01*
G01D02*
X143558D01*
X144400Y731600D01*
G01X111850Y727900D02*
X112733Y728783D01*
X137194D01*
G01X99700Y731037D02*
X107487D01*
X108350Y731900D01*
G01X99700Y731037D02*
Y732300D01*
G01X108350Y727900D02*
X107188Y729062D01*
X103800D01*
G01D02*
Y727700D01*
G01X171100Y247500D02*
Y252828D01*
X163900Y260028D01*
Y298400D01*
X167500Y302000D01*
X170105D01*
X172100Y303995D01*
Y314743D01*
X173277Y315920D01*
G01X134587Y443980D02*
X137344Y446737D01*
G01X142596Y430391D02*
Y437081D01*
X145901Y440386D01*
Y441262D01*
G01X139096Y430391D02*
X135184D01*
X135158Y430365D01*
G01X132204Y434627D02*
X134683D01*
X135158Y434152D01*
Y430365D01*
G01X153100Y439000D02*
X148500D01*
X146086Y436586D01*
Y428854D01*
X140030Y422798D01*
X137136D01*
G01X135159Y426337D02*
Y424775D01*
X137136Y422798D01*
G01X133440Y449150D02*
X134850D01*
X137000Y451300D01*
G01Y457750D02*
X135040Y455790D01*
Y453700D01*
X137000Y451740D01*
Y451300D01*
G01X140570Y488523D02*
X139033Y486986D01*
Y485000D01*
X138959Y484926D01*
Y484737D01*
X137633Y483411D01*
Y479181D01*
X137000Y478548D01*
Y461250D01*
G01D02*
X136467Y460717D01*
X132967D01*
X132959Y460709D01*
G01X164000Y457750D02*
X166085D01*
X170217Y453618D01*
Y401117D01*
X166700Y397600D01*
Y391500D01*
X170144Y388056D01*
Y344097D01*
X167423Y341376D01*
G01X164000Y461250D02*
X162488Y462762D01*
Y469852D01*
X159434Y472906D01*
Y475345D01*
G01D02*
X156319Y478460D01*
Y485374D01*
G01X146150Y452740D02*
X143706Y455184D01*
Y456956D01*
X145000Y458250D01*
G01X140500Y452740D02*
X142188Y454428D01*
Y457062D01*
X141000Y458250D01*
G01X150150Y452740D02*
X151159Y453749D01*
Y455571D01*
X150216Y456514D01*
Y469242D01*
X148552Y470906D01*
Y481518D01*
X148482Y481588D01*
Y483011D01*
X150020Y484549D01*
Y485374D01*
G01X155680Y452680D02*
X152634Y455726D01*
Y456182D01*
X151691Y457125D01*
Y469514D01*
X149766Y471439D01*
Y481971D01*
X150020Y482225D01*
G01X145000Y461750D02*
X143901Y462849D01*
Y468917D01*
X143700Y469118D01*
Y475017D01*
X141700Y477017D01*
Y479339D01*
X146870Y484509D01*
Y485374D01*
G01X141000Y461750D02*
X142426Y463176D01*
Y468612D01*
X142686Y468872D01*
Y474316D01*
X140450Y476552D01*
Y479722D01*
X145338Y484610D01*
Y484731D01*
X145332Y484737D01*
Y486011D01*
X145338Y486017D01*
Y486992D01*
X146870Y488524D01*
G01X162618D02*
X165000Y486142D01*
Y476558D01*
X171000Y470558D01*
Y468000D01*
G01X169000Y463000D02*
Y465215D01*
X168563Y465652D01*
Y469995D01*
X163800Y474758D01*
Y480500D01*
X161080Y483220D01*
Y490136D01*
X162618Y491674D01*
G01X134500Y466000D02*
Y475500D01*
X135727Y476727D01*
Y478499D01*
X135720Y478506D01*
X136758Y479544D01*
Y484711D01*
X137421Y485374D01*
G01X139500Y466500D02*
X138508Y467492D01*
Y483048D01*
X140571Y485111D01*
Y485374D01*
G01X157500Y458000D02*
X161063Y461563D01*
Y469685D01*
X156390Y474358D01*
Y475891D01*
X154781Y477500D01*
Y486986D01*
X156318Y488523D01*
G01X157500Y463000D02*
X159638Y465138D01*
Y469115D01*
X155379Y473374D01*
Y474990D01*
X153169Y477200D01*
Y485374D01*
G01X157500Y468000D02*
X153878Y471622D01*
Y474653D01*
X151631Y476900D01*
Y486986D01*
X153169Y488524D01*
G01X159469D02*
X157931Y486986D01*
Y481369D01*
X161600Y477700D01*
Y472813D01*
X165000Y469413D01*
Y468000D01*
G01X169000Y458000D02*
X166862Y460138D01*
Y464838D01*
X167138Y465114D01*
Y469686D01*
X162700Y474124D01*
Y478900D01*
X159469Y482131D01*
Y485374D01*
G01X133589Y477613D02*
X135883Y479907D01*
Y486986D01*
X137421Y488524D01*
G01X150020Y491674D02*
X150100Y491754D01*
Y494700D01*
G01X164371Y494680D02*
X164937D01*
X167306Y492311D01*
Y491745D01*
X167336Y491715D01*
Y491425D01*
X168666Y490095D01*
X171136D01*
X171152Y490111D01*
X173652D01*
X175215Y491674D01*
G01X161500Y498250D02*
Y497551D01*
X164371Y494680D01*
G01X134521Y595196D02*
X137838Y591879D01*
Y586139D01*
X143268Y580709D01*
Y568132D01*
X144263Y567137D01*
X147900D01*
X148400Y566637D01*
Y560100D01*
X147900Y559600D01*
X145400D01*
X145025Y559225D01*
Y548000D01*
X146512Y546513D01*
Y545412D01*
X146100Y545000D01*
X143350D01*
X142850Y545500D01*
Y550935D01*
X142951Y551036D01*
G01X134521Y617266D02*
Y616272D01*
X132981Y614732D01*
Y610900D01*
X132982Y610899D01*
Y610307D01*
X134463Y608826D01*
Y600578D01*
X138306Y596735D01*
X138307D01*
X139263Y595779D01*
Y586730D01*
X144693Y581300D01*
Y569507D01*
X145638Y568562D01*
X148900D01*
X149836Y567626D01*
Y558836D01*
X149200Y558200D01*
X146900D01*
X145900Y557200D01*
Y548500D01*
X146600Y547800D01*
X149900D01*
X150400Y547300D01*
Y544938D01*
X149437Y543975D01*
X143124D01*
X142148Y542999D01*
Y534195D01*
X140571Y532618D01*
G01X140818Y610945D02*
X142357Y609406D01*
X150494D01*
X155700Y604200D01*
Y589100D01*
X157475Y587325D01*
Y564509D01*
X159162Y562822D01*
Y550262D01*
X149355Y540455D01*
X149344D01*
X148443Y539554D01*
Y535152D01*
X147495Y534204D01*
X144796D01*
X143718Y535282D01*
Y538953D01*
G01X134520Y610944D02*
X137564Y607900D01*
X139892D01*
X140367Y607425D01*
Y604475D01*
X140842Y604000D01*
X141792D01*
X142267Y604475D01*
Y607425D01*
X142742Y607900D01*
X143692D01*
X144167Y607425D01*
Y604475D01*
X144642Y604000D01*
X150680D01*
X151880Y602800D01*
Y590020D01*
X156050Y585850D01*
Y563918D01*
X157737Y562231D01*
Y551037D01*
X148770Y542070D01*
X143686D01*
G01X165864Y533933D02*
X164549Y532618D01*
X162618D01*
G01X137669Y610945D02*
X139207Y612483D01*
X150904D01*
X151879Y611508D01*
Y610308D01*
X152780Y609407D01*
X152793D01*
X157000Y605200D01*
Y590000D01*
X158900Y588100D01*
Y565100D01*
X160000Y564000D01*
X161280D01*
G01X134519Y614095D02*
X136068Y615644D01*
X150895D01*
X151879Y614660D01*
Y613458D01*
X152854Y612483D01*
X154054D01*
X154955Y611582D01*
Y608945D01*
X158178Y605722D01*
Y591411D01*
X160325Y589264D01*
Y567255D01*
X161280Y566300D01*
G01X817405Y779905D02*
X781126Y743626D01*
X514226D01*
X465625Y695025D01*
X360227D01*
X355689Y699563D01*
X342182D01*
X312519Y669900D01*
X212148D01*
X212147Y669901D01*
X210967D01*
X210966Y669902D01*
X207422D01*
X207420Y669900D01*
X207383D01*
X205370Y667887D01*
X164813D01*
X164400Y668300D01*
G01X218937Y791063D02*
X220225Y789775D01*
Y699725D01*
X210352Y689852D01*
X198196D01*
X194585Y693463D01*
X164537D01*
X164500Y693500D01*
G01X137194Y728783D02*
X143817D01*
X144400Y728200D01*
G01X137194Y728783D02*
Y727551D01*
G01X163004Y778459D02*
X164378D01*
G01X164000Y791750D02*
X163004Y790754D01*
Y778459D01*
G01D02*
Y771796D01*
X163800Y771000D01*
G01X161029Y785777D02*
Y771629D01*
X160400Y771000D01*
G01X161029Y785777D02*
X159774D01*
G01X160000Y791750D02*
X161029Y790721D01*
Y785777D01*
G01X163068Y802359D02*
X164442D01*
G01X163800Y820000D02*
X163068Y819268D01*
Y802359D01*
G01D02*
Y796182D01*
X164000Y795250D01*
G01X161093Y813369D02*
X159838D01*
G01X160400Y820000D02*
X161093Y819307D01*
Y813369D01*
G01D02*
Y796343D01*
X160000Y795250D01*
G01X156300Y889470D02*
Y881016D01*
X155575Y880291D01*
Y848527D01*
X155574Y848526D01*
Y836646D01*
X187220Y805000D01*
X208500D01*
X217104Y796396D01*
G01X159449Y889470D02*
Y882149D01*
X157000Y879700D01*
Y837236D01*
X187236Y807000D01*
X210000D01*
X214649Y802351D01*
G01X162599Y889470D02*
Y834401D01*
X187725Y809275D01*
X211225D01*
X212841Y807659D01*
G01X165748Y889470D02*
Y880964D01*
X164575Y879791D01*
Y845575D01*
X164574Y845574D01*
Y835261D01*
X188335Y811500D01*
X212500D01*
X235575Y788425D01*
Y703075D01*
X231500Y699000D01*
G01X153150Y889470D02*
Y837054D01*
X187204Y803000D01*
X207000D01*
X218937Y791063D01*
G01X178692Y352383D02*
X179092Y351983D01*
Y330162D01*
X178279Y329349D01*
Y294219D01*
X172824Y288764D01*
Y257275D01*
X175725Y254374D01*
Y160280D01*
X224832Y111173D01*
Y108069D01*
X221607Y104844D01*
X221593D01*
X220516Y103767D01*
Y103753D01*
X219919Y103156D01*
Y97760D01*
X222252Y95427D01*
X233777D01*
X236800Y98450D01*
G01X218299Y123319D02*
X216583D01*
X215840Y124062D01*
X215626D01*
X179725Y159963D01*
Y193401D01*
X177700Y195426D01*
Y258784D01*
X175430Y261054D01*
G01X260562Y85988D02*
X260553Y85997D01*
X226195D01*
X218494Y93698D01*
Y104917D01*
X221373Y107796D01*
X222179D01*
X223256Y108873D01*
Y110604D01*
X174300Y159560D01*
Y251644D01*
X166687Y259257D01*
Y284643D01*
X176854Y294810D01*
Y332347D01*
G01X222356Y133438D02*
X215092D01*
X187299Y161231D01*
Y193609D01*
X187385Y193695D01*
Y268000D01*
X189500Y270115D01*
Y290264D01*
X187385Y292379D01*
Y333132D01*
X188215Y333962D01*
G01X182855Y337950D02*
X184076Y336729D01*
Y284977D01*
X180362Y281263D01*
Y264219D01*
X181100Y263481D01*
Y196836D01*
X183125Y194811D01*
Y161373D01*
X217036Y127462D01*
X226456D01*
X227947Y128953D01*
X229471D01*
X234719Y123705D01*
X248519D01*
X260719Y111505D01*
Y93609D01*
X258861Y91751D01*
X230001D01*
X228163Y93589D01*
G01X187361Y342183D02*
X185960Y340782D01*
Y291788D01*
X187438Y290310D01*
Y271279D01*
X185874Y269715D01*
Y160640D01*
X215336Y131178D01*
X229262D01*
X235310Y125130D01*
X250058D01*
X262513Y112675D01*
Y93387D01*
X257715Y88589D01*
X228163D01*
G01X224576Y116678D02*
Y120745D01*
X219284Y126037D01*
X216445D01*
X181700Y160782D01*
Y194220D01*
X179675Y196245D01*
Y262890D01*
X176775Y265790D01*
Y286967D01*
X182546Y292738D01*
Y332075D01*
X181838Y332783D01*
G01X257422Y121792D02*
X252659Y126555D01*
X235901D01*
X228596Y133860D01*
X225190D01*
X223171Y135879D01*
X218422D01*
X197438Y156863D01*
Y196000D01*
X199693Y198255D01*
Y207045D01*
X197900Y208838D01*
Y302500D01*
X189500Y310900D01*
Y322575D01*
X189365Y322710D01*
Y329905D01*
G01X193303Y264310D02*
X193949Y263664D01*
Y206269D01*
X196018Y204200D01*
G01X175430Y261054D02*
X174800Y261684D01*
Y264971D01*
X174799Y264972D01*
Y267790D01*
X174800Y267791D01*
Y287884D01*
X180254Y293338D01*
Y321280D01*
X180571Y321597D01*
Y327023D01*
G01X166087Y304350D02*
X167125Y305388D01*
Y316219D01*
X171130Y320224D01*
Y322595D01*
X171825Y323290D01*
Y371719D01*
X187781Y387675D01*
X215968D01*
G01X170062Y304556D02*
X169100Y305518D01*
Y315400D01*
X173105Y319405D01*
Y321776D01*
X173800Y322471D01*
Y370900D01*
X188600Y385700D01*
X197937D01*
G01X215136Y142786D02*
Y143946D01*
X200100Y158982D01*
Y195800D01*
X201668Y197368D01*
Y208532D01*
X200100Y210100D01*
Y303499D01*
X192407Y311192D01*
Y320262D01*
G01X173277Y315920D02*
X174727Y317370D01*
Y320799D01*
X174943Y321015D01*
G01X167687Y329434D02*
X169300Y331047D01*
Y339499D01*
X167423Y341376D01*
G01X196529Y352284D02*
X197882Y350931D01*
Y344961D01*
X189920Y336999D01*
Y335667D01*
X188215Y333962D01*
G01X185970Y358962D02*
X185300Y358292D01*
Y351902D01*
X182855Y349457D01*
Y337950D01*
G01X176674Y344934D02*
Y345078D01*
X176854Y344898D01*
Y332347D01*
G01X187361Y342183D02*
X189309D01*
X195940Y348814D01*
G01X182969Y352641D02*
X180617Y350289D01*
Y334004D01*
X181838Y332783D01*
G01X179381Y369903D02*
Y364281D01*
X178692Y363592D01*
Y352383D01*
G01X192150Y406429D02*
Y406900D01*
X190975Y408075D01*
Y416425D01*
X189650Y417750D01*
Y419800D01*
G01X192950Y403300D02*
Y404435D01*
X194125Y405610D01*
Y406125D01*
X195000Y407000D01*
Y409040D01*
G01X192950Y403300D02*
X196300D01*
X197000Y404000D01*
G01X171434Y398093D02*
X172027Y397500D01*
X237400D01*
X239100Y399200D01*
G01X187600Y409040D02*
Y405150D01*
X189450Y403300D01*
G01D02*
X178400D01*
X175100Y406600D01*
Y416466D01*
X175317Y416683D01*
G01X187600Y411600D02*
X182550D01*
X182300Y411350D01*
G01X181400Y415300D02*
X182300Y414400D01*
Y411350D01*
G01X265288Y481600D02*
X266251Y480637D01*
X268090D01*
X271077Y477650D01*
Y473759D01*
X264875Y467557D01*
Y458181D01*
X260100Y453406D01*
Y422300D01*
X244300Y406500D01*
Y398400D01*
X231600Y385700D01*
X197937D01*
G01D02*
Y384347D01*
G01X189650Y419800D02*
X187600Y417750D01*
Y414160D01*
G01X197713Y431418D02*
X203686Y425445D01*
X207788D01*
G01X197713Y431418D02*
X195661Y433470D01*
Y438356D01*
X197088Y439783D01*
X205483D01*
X210276Y444576D01*
Y448165D01*
G01X199900Y420100D02*
X198100Y421900D01*
X195100D01*
X193150Y419950D01*
Y419800D01*
G01X195000Y414160D02*
X193150Y416010D01*
Y419800D01*
G01X175317Y416683D02*
X178534Y419900D01*
X185000D01*
G01X195000Y411600D02*
X200350D01*
X200500Y411750D01*
G01X197700Y454585D02*
X198712Y453573D01*
Y452368D01*
X197531Y451187D01*
G01D02*
X198725Y449993D01*
Y448175D01*
X197800Y447250D01*
G01X189381Y451394D02*
X190562Y452575D01*
Y454160D01*
X189650Y455072D01*
G01X189381Y451394D02*
X190612Y450163D01*
Y448162D01*
X189600Y447150D01*
G01X193650Y455072D02*
X192537Y453959D01*
Y452575D01*
X193718Y451394D01*
G01D02*
X192587Y450263D01*
Y448163D01*
X193600Y447150D01*
G01X188784Y474485D02*
X187457Y475812D01*
X184615D01*
G01X197700Y458085D02*
X198817Y459202D01*
Y464452D01*
X188784Y474485D01*
G01D02*
X187928Y473629D01*
G01X184615Y477787D02*
X188276D01*
X200792Y465271D01*
Y462653D01*
G01X179192Y472804D02*
X176064D01*
X172309Y476559D01*
G01X189650Y458572D02*
X190623Y459545D01*
Y463947D01*
X181766Y472804D01*
X179192D01*
G01D02*
Y471349D01*
G01X173707Y477955D02*
X176883Y474779D01*
X182585D01*
X189744Y467620D01*
G01X193650Y458572D02*
X192598Y459624D01*
Y464766D01*
X189744Y467620D01*
G01D02*
X190675Y468551D01*
G01X165768Y488524D02*
X166100Y488192D01*
Y477934D01*
X174563Y469471D01*
Y464187D01*
X177500Y461250D01*
G01X181328Y460701D02*
X181214Y460815D01*
X177935D01*
X177500Y461250D01*
G01Y454300D02*
Y457750D01*
G01X185500Y461250D02*
X182393Y458143D01*
X177893D01*
X177500Y457750D01*
G01X165768Y491674D02*
Y490777D01*
X167900Y488645D01*
Y487099D01*
X167300Y486499D01*
Y478986D01*
X176079Y470207D01*
Y466921D01*
X177000Y466000D01*
G01X172065Y488524D02*
X168231Y484686D01*
Y479399D01*
X176954Y470676D01*
Y470564D01*
X181518Y466000D01*
X182000D01*
G01X210300Y457550D02*
X210312D01*
X211312Y458550D01*
Y460687D01*
X210837Y461162D01*
X207072D01*
X191479Y476755D01*
G01X192876Y478152D02*
X207891Y463137D01*
X211656D01*
X213287Y461506D01*
Y458563D01*
X214300Y457550D01*
G01X193195Y480152D02*
X207436Y465911D01*
X216895D01*
X219494Y463312D01*
X221776D01*
X222788Y462300D01*
G01X195077Y481064D02*
X208255Y467886D01*
X210828D01*
G01X178365Y510571D02*
X187319D01*
X198248Y521500D01*
X205000D01*
G01X175215Y510571D02*
X176744Y512100D01*
X177719D01*
X177728Y512109D01*
X179002D01*
X179011Y512100D01*
X186832D01*
X200232Y525500D01*
X201900D01*
G01X172065Y501122D02*
X171841Y501346D01*
X166926D01*
X166608Y501664D01*
G01X199880Y498149D02*
X199333Y498696D01*
X179817D01*
X179002Y499511D01*
X177728D01*
X177262Y499045D01*
X176287D01*
X175215Y497973D01*
G01Y501122D02*
X175882D01*
X177420Y502660D01*
X180451D01*
X181565Y501546D01*
X184535D01*
G01D02*
X189939D01*
X194209Y505816D01*
X200166D01*
X201150Y506800D01*
G01X184535Y501546D02*
Y502910D01*
G01X178365Y501122D02*
X178802Y500685D01*
X179632D01*
X180746Y499571D01*
X190758D01*
X193270Y502083D01*
G01D02*
X195028Y503841D01*
X200109D01*
X201150Y502800D01*
G01X194148Y501205D02*
X193270Y502083D01*
G01X184664Y485372D02*
X185772D01*
X187300Y486900D01*
G01X172065Y494823D02*
X171508D01*
X169514Y492829D01*
G01X204319Y478610D02*
X202671D01*
X189203Y492078D01*
X182274D01*
X181870Y491674D01*
X178365D01*
G01X206487Y476635D02*
X201852D01*
X188384Y490103D01*
X183093D01*
X181514Y488524D01*
G01X205397Y488387D02*
X198732D01*
X190966Y496153D01*
X183174D01*
X182892Y496435D01*
X173603D01*
X172065Y497973D01*
G01X178365Y494823D02*
X179010Y494178D01*
X190147D01*
X197913Y486412D01*
X199809D01*
G01X198000Y493500D02*
X193680Y497820D01*
X191483D01*
X180872Y497821D01*
X179454D01*
X179302Y497973D01*
X178365D01*
G01X198000Y493500D02*
X204362D01*
X204862Y494000D01*
X206700D01*
G01X175215Y513721D02*
X176794Y515300D01*
X185700D01*
X201400Y531000D01*
Y532400D01*
G01X209750Y538500D02*
X207912Y536662D01*
X201400D01*
X192595Y527857D01*
X174578D01*
X173040Y526319D01*
X172065D01*
G01X209750Y542500D02*
X208250Y541000D01*
X202200D01*
X190669Y529469D01*
X178365D01*
G01X175215D02*
X176746Y531000D01*
X177721D01*
X177728Y531007D01*
X186407D01*
X199900Y544500D01*
G01X172065Y529469D02*
X173603Y531007D01*
Y536329D01*
X174654Y537380D01*
X175852D01*
X176972Y538500D01*
X180500D01*
X182000Y540000D01*
Y568815D01*
X186416Y573231D01*
G01X173618Y516881D02*
Y518965D01*
X173603Y518980D01*
Y521558D01*
X175215Y523170D01*
G01X181811Y524978D02*
X180003Y523170D01*
X178365D01*
G01X185355Y537874D02*
X184787Y537306D01*
X177306D01*
X175767Y535767D01*
X175216D01*
G01X184500Y545250D02*
X185355Y544395D01*
Y537874D01*
G01X168599Y527221D02*
X170222Y525598D01*
X170300D01*
X171117Y524781D01*
X173677D01*
X175215Y526319D01*
G01X178365Y513721D02*
X186437D01*
X203216Y530500D01*
X206200D01*
G01X178000Y547000D02*
X180638Y544362D01*
Y540638D01*
X179500Y539500D01*
X175797D01*
X175215Y538918D01*
G01X173000Y542500D02*
X170527Y540027D01*
Y537377D01*
X168916Y535766D01*
G01X178000Y542000D02*
X176456Y540456D01*
X174456D01*
X172918Y538918D01*
X172065D01*
G01X173000Y552500D02*
Y550524D01*
X169500Y547024D01*
Y542650D01*
X168916Y542066D01*
G01X167000Y545500D02*
Y543847D01*
X167304Y543543D01*
Y540454D01*
X165766Y538916D01*
G01X173000Y547500D02*
X170500Y545000D01*
Y541475D01*
X168916Y539891D01*
Y538916D01*
G01X210510Y562800D02*
X200793D01*
X198862Y560869D01*
Y547242D01*
X184238Y532618D01*
X178365D01*
G01X196782Y563564D02*
X198082Y564864D01*
X199009D01*
X199559Y565414D01*
X199846D01*
X201429Y566997D01*
G01X197334Y567232D02*
X194968D01*
X193600Y568600D01*
Y569800D01*
G01D02*
X194550Y570750D01*
X197500D01*
G01X186416Y573231D02*
X191500Y578315D01*
Y581250D01*
G01X184500Y548750D02*
Y564193D01*
X184189Y564504D01*
G01X259633Y715867D02*
X263500Y712000D01*
X307068D01*
X311430Y707638D01*
Y698398D01*
X294332Y681300D01*
X216876D01*
X216875Y681301D01*
X215695D01*
X215694Y681302D01*
X200238D01*
X200236Y681300D01*
X194652D01*
X191452Y684500D01*
X189000D01*
G01X321500Y706500D02*
Y702422D01*
X315705Y696627D01*
Y696625D01*
X296105Y677025D01*
X215103D01*
X215102Y677026D01*
X213922D01*
X213921Y677027D01*
X202011D01*
X202009Y677025D01*
X177972D01*
X177147Y676200D01*
X173400D01*
X171300Y678300D01*
G01X175200Y678500D02*
X175250Y678450D01*
X201418D01*
X201420Y678452D01*
X214512D01*
X214513Y678451D01*
X215693D01*
X215694Y678450D01*
X295514D01*
X314280Y697216D01*
Y697218D01*
X318000Y700938D01*
Y709048D01*
X328145Y719193D01*
X382145D01*
X480952Y818000D01*
X481000D01*
G01X260816Y710184D02*
X261706Y709294D01*
X307758D01*
X310005Y707047D01*
Y698989D01*
X293741Y682725D01*
X217467D01*
X217466Y682726D01*
X216286D01*
X216285Y682727D01*
X199647D01*
X199645Y682725D01*
X195243D01*
X191630Y686338D01*
X186838D01*
X185000Y684500D01*
G01X167000Y686500D02*
X169688Y689188D01*
X192812D01*
X196425Y685575D01*
X198463D01*
X198465Y685577D01*
X217467D01*
X217468Y685576D01*
X218648D01*
X218649Y685575D01*
X221075D01*
X237000Y701500D01*
Y790500D01*
X214000Y813500D01*
X189500D01*
X174265Y828735D01*
G01X170257Y722694D02*
X171631D01*
G01X171300Y736050D02*
X170257Y735007D01*
Y722694D01*
G01D02*
Y716643D01*
X171000Y715900D01*
G01X168282Y730499D02*
X167027D01*
G01X167300Y736050D02*
X168282Y735068D01*
Y730499D01*
G01D02*
Y716582D01*
X167600Y715900D01*
G01X170355Y747695D02*
X171729D01*
G01X171000Y764900D02*
X170355Y764255D01*
Y747695D01*
G01D02*
Y740495D01*
X171300Y739550D01*
G01X168380Y759093D02*
Y740630D01*
X167300Y739550D01*
G01X168380Y759093D02*
X167125D01*
G01X167600Y764900D02*
X168380Y764120D01*
Y759093D01*
G01X241000Y712500D02*
X238500Y715000D01*
Y792500D01*
X215000Y816000D01*
X190500D01*
X169840Y836660D01*
G01X172048Y889470D02*
Y877248D01*
X168500Y873700D01*
Y838000D01*
X169840Y836660D01*
G01X168898Y889470D02*
Y882098D01*
X166000Y879200D01*
Y837000D01*
X174265Y828735D01*
G01X181496Y889470D02*
Y882677D01*
X180929Y882110D01*
Y876087D01*
X176118Y871276D01*
Y868382D01*
X176900Y867600D01*
G01X178347Y889470D02*
Y882677D01*
X178954Y882070D01*
Y876906D01*
X174143Y872095D01*
Y868243D01*
X173500Y867600D01*
G01X232600Y98550D02*
X230600Y100550D01*
X224889D01*
X223641Y99302D01*
G01X205840Y325381D02*
X207000Y324221D01*
Y320206D01*
X227006Y300200D01*
X255854D01*
X263555Y292499D01*
X272507D01*
X322681Y242325D01*
X350381D01*
X359599Y233107D01*
Y197306D01*
X392105Y164800D01*
X399700D01*
X436775Y127725D01*
X465874D01*
X469196Y131047D01*
X483209D01*
X493260Y141098D01*
X493261D01*
X493263Y141100D01*
X505716D01*
X510958Y135858D01*
Y124962D01*
X513795Y122125D01*
Y116989D01*
X515650Y115134D01*
Y94834D01*
X524151Y86333D01*
Y84764D01*
G01X210177Y325381D02*
X208975Y324179D01*
Y321025D01*
X227825Y302175D01*
X256673D01*
X264374Y294474D01*
X273326D01*
X323500Y244300D01*
X351200D01*
X361574Y233926D01*
Y198125D01*
X392924Y166775D01*
X400519D01*
X437594Y129700D01*
X465055D01*
X468377Y133022D01*
X482390D01*
X492441Y143073D01*
X492442D01*
X492444Y143075D01*
X506535D01*
X507110Y143650D01*
X510699D01*
X511400Y142949D01*
Y140104D01*
X517686Y133820D01*
X517820D01*
G01X265288Y477600D02*
X266350Y478662D01*
X267271D01*
X269102Y476831D01*
Y474578D01*
X262900Y468376D01*
Y459000D01*
X258125Y454225D01*
Y423119D01*
X242325Y407319D01*
Y399219D01*
X230781Y387675D01*
X215968D01*
G01D02*
Y389018D01*
G01X217190Y428485D02*
X215338Y430337D01*
Y431285D01*
G01X217190Y428485D02*
Y425947D01*
X216688Y425445D01*
X214888D01*
G01D02*
X211288D01*
G01X212200Y428800D02*
X212074Y428926D01*
X212019D01*
X211000Y429945D01*
Y435500D01*
X210095Y436405D01*
X207938D01*
G01X210888Y441845D02*
Y440887D01*
X210115Y440114D01*
Y438592D01*
X210120Y438587D01*
X207938Y436405D01*
G01Y431285D02*
Y425595D01*
X207788Y425445D01*
G01X215338Y436405D02*
Y440895D01*
X214388Y441845D01*
G01D02*
X215550Y443007D01*
Y447000D01*
X214350Y448200D01*
G01X199900Y420100D02*
Y415300D01*
X200100Y415100D01*
G01X215338Y433845D02*
X218888D01*
X220838Y431895D01*
G01D02*
Y428917D01*
X221699Y428056D01*
G01X207938Y433845D02*
X207688Y434095D01*
X202638D01*
G01D02*
Y431000D01*
X202469Y430831D01*
Y429873D01*
G01X200500Y411750D02*
X203150D01*
X205100Y413700D01*
G01X201700Y454585D02*
X200687Y453572D01*
Y452368D01*
X201868Y451187D01*
G01D02*
X200700Y450019D01*
Y448350D01*
X201800Y447250D01*
G01X227700Y476537D02*
X228690Y477527D01*
X231091D01*
X231393Y477829D01*
G01X214252Y479619D02*
X215296Y478575D01*
X220920D01*
X223920Y475575D01*
X226738D01*
X227700Y476537D01*
G01Y472200D02*
X227225D01*
X225825Y473600D01*
X223101D01*
X220101Y476600D01*
X215233D01*
X214252Y475619D01*
G01X231393Y473829D02*
X229329D01*
X227700Y472200D01*
G01X201700Y458085D02*
X200792Y458993D01*
Y462653D01*
G01D02*
X202185D01*
G01X204319Y479895D02*
Y478610D01*
G01D02*
X209743D01*
X210752Y479619D01*
G01X206487Y476635D02*
Y475373D01*
G01X210752Y475619D02*
X209736Y476635D01*
X206487D01*
G01X210300Y454050D02*
X211312Y453038D01*
Y449201D01*
X210276Y448165D01*
G01X214350Y448200D02*
X213287Y449263D01*
Y453037D01*
X214300Y454050D01*
G01D02*
X216969D01*
X218774Y452245D01*
G01X226288Y462300D02*
X226351Y462363D01*
X230572D01*
G01X241446Y452004D02*
X236096D01*
X233300Y454800D01*
Y459635D01*
X230572Y462363D01*
G01X235100Y466250D02*
X230588D01*
X230571Y466267D01*
G01X226288Y466300D02*
X230538D01*
X230571Y466267D01*
G01X224548Y470077D02*
Y468040D01*
X226288Y466300D01*
G01X210300Y457550D02*
X206285D01*
G01X214300D02*
X218425D01*
G01X222788Y462300D02*
Y459050D01*
X223334Y458504D01*
G01X210828Y467886D02*
X217714D01*
X220313Y465287D01*
X221775D01*
X222788Y466300D01*
G01X210828Y467886D02*
Y469403D01*
G01X228298Y488100D02*
X228022Y487824D01*
X217330D01*
X216143Y486637D01*
X215540D01*
X214473Y487704D01*
G01X228298Y488100D02*
X230127Y489929D01*
X231393D01*
G01X228347Y484700D02*
X227198Y485849D01*
X218149D01*
X216962Y484662D01*
X215431D01*
X214473Y483704D01*
G01X228347Y484700D02*
X229576Y485929D01*
X231393D01*
G01X290838Y501600D02*
X290058D01*
X280752Y510906D01*
X279988D01*
X276602Y514292D01*
X253764D01*
X242286Y502814D01*
X240114D01*
X227100Y489800D01*
X219700D01*
G01X210000Y495744D02*
X208956D01*
X206700Y498000D01*
G01X199880Y498149D02*
X202631Y500900D01*
X205200D01*
X206700Y499400D01*
Y498000D01*
G01X205397Y488387D02*
Y489870D01*
G01X210973Y487704D02*
X210290Y487021D01*
X209618D01*
X208252Y488387D01*
X205397D01*
G01X199809Y486412D02*
X207433D01*
X208799Y485046D01*
X209631D01*
X210973Y483704D01*
G01X199809Y486412D02*
Y485199D01*
G01X210000Y491744D02*
X208956D01*
X206700Y494000D01*
G01X204650Y506800D02*
X205663Y505787D01*
X208807D01*
X212933Y501661D01*
X221643D01*
X221806Y501824D01*
X222150D01*
X225101Y504775D01*
X225375D01*
X226300Y505700D01*
G01D02*
X227100Y504900D01*
X229300D01*
X230400Y506000D01*
X231350D01*
G01X226530Y502307D02*
X225427D01*
X222969Y499849D01*
X222625D01*
X222462Y499686D01*
X212114D01*
X207988Y503812D01*
X205662D01*
X204650Y502800D01*
G01X226530Y502307D02*
X227148Y502925D01*
X229300D01*
X230225Y502000D01*
X231350D01*
G01X217000Y534750D02*
X213500D01*
X213250Y534500D01*
G01X221000Y534750D02*
X217000D01*
G01X225000D02*
X221000D01*
G01X225000D02*
X232350D01*
X232600Y535000D01*
G01X201400Y532400D02*
X203500Y534500D01*
X209750D01*
G01X221000Y521750D02*
X218945D01*
X218707Y521988D01*
X216593D01*
X216355Y521750D01*
X213500D01*
X213250Y521500D01*
G01X225000Y521750D02*
X229000D01*
G01X225000D02*
X221000D01*
G01X229000D02*
X232840D01*
X233701Y522611D01*
G01X205000Y521500D02*
X209750D01*
G01X221000Y525750D02*
X220220Y524970D01*
X217291D01*
G01X225000Y525750D02*
X221000D01*
G01X229000D02*
X225000D01*
G01X217291Y524970D02*
X213780D01*
X213250Y525500D01*
G01X201900D02*
X209750D01*
G01X222700Y546500D02*
X220600D01*
X219700Y547400D01*
Y550500D01*
G01X199900Y544500D02*
X201900Y546500D01*
X209750D01*
G01X213250Y530500D02*
X214762Y532012D01*
X262500D01*
G01X206200Y530500D02*
X209750D01*
G01Y550500D02*
X205300D01*
X203300Y548500D01*
G01X201429Y566997D02*
X201500Y567068D01*
Y570750D01*
G01X226250Y550500D02*
Y554500D01*
G01X234777Y550569D02*
X234708Y550500D01*
X226250D01*
G01X222750D02*
X222700Y550450D01*
Y546500D01*
G01X218780Y560082D02*
X219031D01*
X221049Y562100D01*
X222800D01*
G01X222750Y558500D02*
X222800Y558550D01*
Y562100D01*
G01X226250Y558500D02*
X229800D01*
G01X216241Y563095D02*
X215946Y562800D01*
X210510D01*
G01X201000Y674000D02*
X202602Y675602D01*
X213330D01*
X213331Y675601D01*
X214511D01*
X214512Y675600D01*
X296710D01*
X324574Y703464D01*
Y709074D01*
X329913Y714413D01*
G01X206952Y655370D02*
X207122Y655200D01*
X216795D01*
X219520Y657925D01*
X826979D01*
X885442Y599462D01*
X1275462D01*
X1314422Y638422D01*
G01X202609Y706502D02*
X203983D01*
G01X203500Y712750D02*
X202609Y711859D01*
Y706502D01*
G01D02*
Y692661D01*
X203270Y692000D01*
X203300D01*
G01X200634Y698698D02*
X199379D01*
G01X199500Y712750D02*
X200634Y711616D01*
Y698698D01*
G01D02*
Y692905D01*
X199900Y692171D01*
Y692000D01*
G01X219000Y694000D02*
X221650Y696650D01*
Y791850D01*
X217104Y796396D01*
G01X202608Y762392D02*
Y748162D01*
X203270Y747500D01*
X203300D01*
G01X200633Y752617D02*
Y748404D01*
X199900Y747671D01*
Y747500D01*
G01X202641Y733445D02*
X204015D01*
G01X203300Y741000D02*
X202641Y740341D01*
Y733445D01*
G01D02*
Y717109D01*
X203500Y716250D01*
G01X200666Y721528D02*
X199411D01*
G01X199900Y741000D02*
X200666Y740234D01*
Y721528D01*
G01D02*
Y717416D01*
X199500Y716250D01*
G01X203500Y768250D02*
X202608Y767358D01*
Y762392D01*
G01D02*
X204186D01*
G01X200633Y752617D02*
X199378D01*
G01X199500Y768250D02*
X200633Y767117D01*
Y752617D01*
G01X202640Y779192D02*
X204014D01*
G01X203300Y796500D02*
X202640Y795840D01*
Y779192D01*
G01D02*
Y772610D01*
X203500Y771750D01*
G01X200665Y790376D02*
Y772915D01*
X199500Y771750D01*
G01X200665Y790376D02*
X199410D01*
G01X199900Y796500D02*
X200665Y795735D01*
Y790376D01*
G01X258100Y93589D02*
X248692D01*
X243831Y98450D01*
X236800D01*
G01X249995Y98708D02*
X252600D01*
X255300Y101408D01*
X257912D01*
G01X266500Y239400D02*
Y243200D01*
X266200Y243500D01*
G01X258500Y391200D02*
X277700Y410400D01*
Y463300D01*
X285500Y471100D01*
Y480300D01*
X289000Y483800D01*
Y499762D01*
X290838Y501600D01*
G01X251700Y425200D02*
Y429200D01*
G01X245960Y468300D02*
X249950D01*
X251800Y466450D01*
G01D02*
Y470100D01*
G01X248500Y465000D02*
X247800Y464300D01*
X242100D01*
X240840Y463040D01*
Y460900D01*
G01X235100Y462750D02*
X236950Y460900D01*
X240840D01*
G01X254250Y477500D02*
X255262Y478512D01*
X256625D01*
X257400Y477737D01*
Y477300D01*
G01D02*
X257775D01*
X259088Y478613D01*
X260775D01*
X261788Y477600D01*
G01X251800Y462950D02*
X251150D01*
X249100Y460900D01*
X245960D01*
G01X241446Y452004D02*
X247262D01*
X251464Y456206D01*
Y457440D01*
X251800Y457776D01*
Y462950D01*
G01X240840Y468300D02*
X237945D01*
X237224Y467579D01*
X236429D01*
X235100Y466250D01*
G01X246300Y478600D02*
X243850D01*
X243250Y478000D01*
G01X246300Y478600D02*
X246900Y479200D01*
X249050D01*
X250750Y477500D01*
G01X243400Y468300D02*
Y473350D01*
X243650Y473600D01*
G01D02*
X247661D01*
G01X243400Y460900D02*
Y455850D01*
X243650Y455600D01*
G01X247473D02*
X243650D01*
G01X249750Y486000D02*
X246900D01*
X246300Y485400D01*
G01D02*
X245700Y486000D01*
X243250D01*
G01X249750Y490000D02*
X248549Y488799D01*
X246407D01*
G01D02*
X244451D01*
X243250Y490000D01*
G01X251000Y498150D02*
Y496350D01*
X253250Y494100D01*
G01X251000Y498150D02*
X252650D01*
X256300Y494500D01*
G01X249750Y494100D02*
X248700Y495150D01*
Y497700D01*
X247700Y498700D01*
X245300D01*
X244100Y499900D01*
G01X254250Y481500D02*
X255263Y480487D01*
X256625D01*
X257400Y481262D01*
Y481637D01*
G01D02*
X257837D01*
X258886Y480588D01*
X260776D01*
X261788Y481600D01*
G01X253250Y486000D02*
X256300D01*
G01D02*
X259700D01*
X260500Y486800D01*
G01X253250Y490000D02*
X256300D01*
G01X259800Y492500D02*
X258700D01*
X257600Y491400D01*
Y491300D01*
X256300Y490000D01*
G01X246300Y482000D02*
X243250D01*
G01X250750Y481500D02*
X246800D01*
X246300Y482000D01*
G01X306900Y529100D02*
X292750D01*
X289838Y532012D01*
X262500D01*
G01X260250Y588500D02*
X256400D01*
X254400Y590500D01*
X253500D01*
G01X260250Y593000D02*
X259838D01*
X257413Y590575D01*
Y590500D01*
G01X263750Y588500D02*
X267095Y585155D01*
X267540D01*
G01X263750Y593000D02*
X269170D01*
X269335Y593165D01*
G01X241521Y654021D02*
X242250Y654750D01*
X257110D01*
X271500Y640360D01*
Y639500D01*
G01X302406Y706031D02*
X298012Y701637D01*
X255363D01*
X248890Y708110D01*
G01X247638Y889470D02*
Y881354D01*
X245762Y879478D01*
Y711238D01*
X248890Y708110D01*
G01X298406Y706000D02*
X295468Y703062D01*
X258938D01*
X255968Y706032D01*
G01X250788Y889470D02*
Y882488D01*
X247187Y878887D01*
Y714813D01*
X255968Y706032D01*
G01X306406Y706031D02*
X300587Y700212D01*
X251288D01*
X249797Y701703D01*
G01X244488Y889470D02*
Y880220D01*
X244337Y880069D01*
Y707163D01*
X249797Y701703D01*
G01X307178Y760181D02*
X307171Y760188D01*
X302739D01*
X300790Y762137D01*
X297348D01*
X297217Y762268D01*
X282248D01*
X281091Y763425D01*
X262425D01*
X252500Y753500D01*
Y718500D01*
X260816Y710184D01*
G01X321678Y760181D02*
X319890Y761969D01*
X317084D01*
X317052Y761937D01*
X314348D01*
X314316Y761969D01*
X308189D01*
X306596Y763562D01*
X297939D01*
X297808Y763693D01*
X282839D01*
X281681Y764851D01*
X260851D01*
X250500Y754500D01*
Y716000D01*
X254212Y712288D01*
G01X278050Y733267D02*
Y731675D01*
X276837Y730462D01*
X262462D01*
X258100Y726100D01*
G01X289678Y760181D02*
X282319D01*
X280500Y762000D01*
X263016D01*
X253925Y752909D01*
Y721575D01*
X259633Y715867D01*
G01X263000Y755750D02*
X255350Y748100D01*
Y724650D01*
X257728Y722272D01*
G01X263000Y752250D02*
Y749200D01*
X263500Y748700D01*
G01D02*
X263950D01*
X267500Y752250D01*
G01X271231Y237031D02*
X273800Y239600D01*
Y240000D01*
G01X288270Y365240D02*
X289300Y364210D01*
Y335353D01*
X307425Y317228D01*
Y309838D01*
G01X293800Y436100D02*
X298300Y431600D01*
Y381223D01*
X308637Y370886D01*
Y320196D01*
X310485Y318348D01*
Y314670D01*
G01X295876Y520800D02*
Y518790D01*
X297423Y517243D01*
X297425D01*
X299653Y515015D01*
Y481985D01*
X298564Y480896D01*
Y471361D01*
X293777Y466574D01*
X293776Y456788D01*
Y441324D01*
X300300Y434800D01*
Y408600D01*
X299725Y408025D01*
Y381814D01*
X316669Y364870D01*
Y355981D01*
X321454Y351196D01*
G01X359061Y335014D02*
Y336478D01*
X330942Y364597D01*
Y377058D01*
X301900Y406100D01*
Y436100D01*
X295202Y442798D01*
Y465983D01*
X299989Y470770D01*
Y480305D01*
X301078Y481394D01*
Y502378D01*
X303800Y505100D01*
G01X301170Y462780D02*
X300270Y461880D01*
X299257D01*
X297195Y459818D01*
Y456805D01*
X304300Y449700D01*
Y409200D01*
X333097Y380403D01*
Y364639D01*
X359898Y337838D01*
X375068D01*
X385104Y327802D01*
Y248740D01*
X371554Y235190D01*
Y199310D01*
X396414Y174450D01*
X403702D01*
X437414Y140738D01*
X479248D01*
X489835Y151325D01*
X523401D01*
X526826Y147900D01*
X553100D01*
X560100Y154900D01*
X606902D01*
X609354Y152448D01*
Y150663D01*
X607812Y149121D01*
G01X301162Y459290D02*
X300549Y459905D01*
Y459903D01*
X300548Y459905D01*
X300312Y459903D01*
X300074D01*
X299170Y458999D01*
Y457624D01*
X306275Y450519D01*
Y410019D01*
X335072Y381222D01*
Y365458D01*
X360717Y339813D01*
X375887D01*
X387079Y328621D01*
Y247921D01*
X373529Y234371D01*
Y200129D01*
X397233Y176425D01*
X404521D01*
X438233Y142713D01*
X478429D01*
X489016Y153300D01*
X524220D01*
X527645Y149875D01*
X552281D01*
X559281Y156875D01*
X607721D01*
X611329Y153267D01*
Y150663D01*
X611331Y150661D01*
Y150565D01*
X612812Y149084D01*
G01X294250Y578500D02*
X290335D01*
X290000Y578165D01*
G01D02*
X285700D01*
G01X294250Y583000D02*
X290000D01*
X289835Y583165D01*
G01D02*
X285900D01*
G01X294250Y588500D02*
X290170D01*
X289835Y588165D01*
G01D02*
X285613D01*
X285606Y588172D01*
G01X267540Y585155D02*
X269000Y586615D01*
Y589000D01*
G01X269335Y593165D02*
X272751D01*
X272843Y593257D01*
Y593265D01*
X273134D01*
G01X266980Y723854D02*
Y718848D01*
X267011Y718817D01*
G01X274406Y723148D02*
X273387D01*
X269056Y718817D01*
X267011D01*
G01X275609Y726886D02*
X275050Y727445D01*
X272137D01*
X270430Y725738D01*
G01X278406Y723148D02*
Y724089D01*
X275609Y726886D01*
G01X287278Y729031D02*
X285217D01*
X284038Y727852D01*
X280271D01*
X279045Y729078D01*
G01X286406Y723148D02*
X287278Y724020D01*
Y729031D01*
G01X293678Y760181D02*
X294209Y760712D01*
X299500D01*
X300488Y759724D01*
Y750431D01*
X298812Y748755D01*
Y740093D01*
X301738Y737167D01*
Y734510D01*
X297192Y729964D01*
X294579D01*
X293738Y729123D01*
G01D02*
Y728565D01*
X296132Y726171D01*
G01X290500Y723250D02*
X294404D01*
X294506Y723148D01*
G01D02*
Y724545D01*
X296132Y726171D01*
G01X295678Y732681D02*
X293681D01*
X290778Y729778D01*
Y726472D01*
X290799Y726451D01*
Y726333D01*
X290720D01*
G01X282406Y723148D02*
Y723314D01*
X285333Y726241D01*
G01X298620Y728596D02*
X300524Y730500D01*
X302000D01*
G01X298554Y723163D02*
Y728530D01*
X298620Y728596D01*
G01X295560Y743250D02*
Y739272D01*
X295678Y739154D01*
Y736181D01*
G01D02*
X297192D01*
X297373Y736000D01*
X299500D01*
G01X278282Y743219D02*
X281281D01*
X283196Y741304D01*
Y739009D01*
X283004D01*
G01X278050Y736767D02*
X280762D01*
X283004Y739009D01*
G01X282378Y768681D02*
X278681D01*
X278500Y768500D01*
G01X283500Y765631D02*
X282855Y766276D01*
X279724D01*
X278500Y767500D01*
Y768500D01*
G01X293692Y765571D02*
X293690D01*
Y765559D01*
X293631Y765500D01*
X291700D01*
X290830Y766370D01*
Y768755D01*
G01X295079Y768600D02*
X294924Y768755D01*
X290830D01*
G01X279500Y759750D02*
X281500Y757750D01*
Y752000D01*
G01X286906Y768648D02*
Y765903D01*
X287115Y765694D01*
Y765584D01*
G01X299164Y768841D02*
Y765711D01*
X299184Y765691D01*
G01X285000Y752250D02*
Y757000D01*
G01X290440Y749750D02*
Y754238D01*
X289678Y755000D01*
Y756681D01*
G01D02*
X289359Y757000D01*
X285000D01*
G01X267500Y752250D02*
X269250D01*
X271781Y749719D01*
X273162D01*
G01X293678Y756681D02*
X293997Y757000D01*
X297500D01*
G01X293000Y749750D02*
Y752500D01*
X294000Y753500D01*
X297000D01*
X297500Y754000D01*
Y757000D01*
G01X275722Y749719D02*
Y755773D01*
X275900Y755951D01*
G01X279500Y756250D02*
X276199D01*
X275900Y755951D01*
G01X525820Y133820D02*
X522768Y136872D01*
Y139668D01*
X523500Y140400D01*
Y142301D01*
X520726Y145075D01*
X492428D01*
X491851Y144498D01*
X491850D01*
X481800Y134448D01*
X464378D01*
X461730Y131800D01*
X437510D01*
X401110Y168200D01*
X393601D01*
X364132Y197669D01*
Y318068D01*
X350300Y331900D01*
X340750D01*
X321454Y351196D01*
G01X567458Y84764D02*
Y87526D01*
X565909Y89075D01*
X565893D01*
X559500Y95468D01*
Y106242D01*
X567815Y114557D01*
Y137795D01*
X565190Y140420D01*
Y141389D01*
X564693Y141886D01*
Y143825D01*
X564218Y144300D01*
X561200D01*
X559889Y142989D01*
X524911D01*
X521400Y146500D01*
X491836D01*
X481209Y135873D01*
X463787D01*
X461339Y133425D01*
X437901D01*
X401701Y169625D01*
X394192D01*
X366267Y197550D01*
Y238861D01*
X370825Y243419D01*
Y318281D01*
X359581Y329525D01*
X355335D01*
X321076Y363784D01*
Y367727D01*
X316927Y371876D01*
X313938D01*
X313100Y371038D01*
G01X574345Y133780D02*
X572055Y136070D01*
Y138455D01*
X568369Y142141D01*
Y144331D01*
X567739Y144961D01*
X566351D01*
X565037Y146275D01*
X560381D01*
X559070Y144964D01*
X525730D01*
X522219Y148475D01*
X491017D01*
X480390Y137848D01*
X462968D01*
X460520Y135400D01*
X438720D01*
X402520Y171600D01*
X395011D01*
X368242Y198369D01*
Y238042D01*
X372800Y242600D01*
Y319100D01*
X360400Y331500D01*
X356154D01*
X323051Y364603D01*
Y368546D01*
X320814Y370783D01*
G01X321708Y371677D02*
X320814Y370783D01*
G01D02*
X317746Y373851D01*
X313687D01*
X313100Y374438D01*
G01X306521Y463576D02*
X309125Y460972D01*
Y412954D01*
X337924Y384155D01*
Y366639D01*
X358438Y346125D01*
X375881D01*
X390575Y331431D01*
Y247385D01*
X377701Y234511D01*
Y199992D01*
X398418Y179275D01*
X405703D01*
X438378Y146600D01*
X478103D01*
X487653Y156150D01*
X525044D01*
X529519Y160625D01*
X540119D01*
X542681Y158063D01*
X556437D01*
X558099Y159725D01*
X607477D01*
X608850Y161098D01*
X635976D01*
X645625Y151449D01*
Y144419D01*
X643635Y142429D01*
Y134265D01*
X640975Y131605D01*
Y128000D01*
X643518Y125457D01*
G01X647000Y143000D02*
X647600Y143600D01*
Y152268D01*
X636795Y163073D01*
X608031D01*
X606658Y161700D01*
X557280D01*
X555618Y160038D01*
X543500D01*
X540938Y162600D01*
X540476D01*
X540475Y162601D01*
X528701D01*
X524225Y158125D01*
X486834D01*
X477284Y148575D01*
X439197D01*
X406522Y181250D01*
X399237D01*
X379676Y200811D01*
Y233692D01*
X392550Y246566D01*
Y332250D01*
X376700Y348100D01*
X359257D01*
X339899Y367458D01*
Y384974D01*
X311100Y413773D01*
Y461791D01*
X307340Y465551D01*
X304888D01*
X304293Y466146D01*
G01X304400Y511400D02*
X305638Y510162D01*
Y490539D01*
X302503Y487404D01*
Y480803D01*
X301602Y479902D01*
Y466198D01*
X303700Y464100D01*
Y458800D01*
X307700Y454800D01*
Y410610D01*
X336498Y381812D01*
Y366049D01*
X357847Y344700D01*
X375290D01*
X389150Y330840D01*
Y247976D01*
X375637Y234463D01*
Y200037D01*
X397824Y177850D01*
X405112D01*
X438824Y144138D01*
X477838D01*
X488425Y154725D01*
X526125D01*
X530600Y159200D01*
X539528D01*
X542090Y156638D01*
X557028D01*
X558690Y158300D01*
X609217D01*
X609777Y158860D01*
G01X356953Y353653D02*
Y358268D01*
X346109Y369112D01*
Y387739D01*
X320581Y413267D01*
Y430319D01*
X313500Y437400D01*
G01X359403Y351203D02*
Y357834D01*
X347534Y369703D01*
Y388330D01*
X322006Y413858D01*
Y432494D01*
X313500Y441000D01*
G01X352003Y358603D02*
X343259Y367347D01*
Y386557D01*
X317731Y412085D01*
Y425172D01*
X313300Y429603D01*
G01X354505Y356102D02*
Y358700D01*
X344684Y368521D01*
Y387148D01*
X319156Y412676D01*
Y428144D01*
X313294Y434006D01*
G01X360820Y359299D02*
Y381172D01*
X326281Y415711D01*
Y462578D01*
X322268Y466591D01*
G01X363270Y356940D02*
Y380738D01*
X327706Y416302D01*
Y464590D01*
X322305Y469991D01*
G01X355872Y363965D02*
Y382088D01*
X323431Y414529D01*
Y458269D01*
X321900Y459800D01*
G01X358362Y361649D02*
Y381614D01*
X324856Y415120D01*
Y460378D01*
X322036Y463198D01*
G01X370700Y353900D02*
Y375844D01*
X330556Y415988D01*
Y465772D01*
X325751Y470577D01*
Y507851D01*
X327512Y509612D01*
G01X650500Y133750D02*
X649500Y134750D01*
Y152384D01*
X637386Y164498D01*
X607440D01*
X606067Y163125D01*
X556689D01*
X555027Y161463D01*
X544495D01*
X541932Y164026D01*
X527226D01*
X522750Y159550D01*
X485565D01*
X478150Y152135D01*
X462688D01*
X459348Y155475D01*
X434313D01*
X407113Y182675D01*
X399829D01*
X381101Y201403D01*
Y233101D01*
X393975Y245975D01*
Y354585D01*
X331981Y416579D01*
Y466363D01*
X327176Y471168D01*
Y503887D01*
X327589Y504300D01*
G01X400400Y189100D02*
X404217Y192917D01*
Y236427D01*
X395400Y245244D01*
Y355176D01*
X333406Y417170D01*
Y467630D01*
X329014Y472022D01*
G01X421757Y177999D02*
X407067Y192689D01*
Y237609D01*
X398367Y246309D01*
Y321467D01*
X398368Y321468D01*
Y356240D01*
X336256Y418352D01*
Y473460D01*
X333102Y476614D01*
Y485902D01*
G01X330000Y496213D02*
Y477700D01*
X334831Y472869D01*
Y417761D01*
X396825Y355767D01*
Y245835D01*
X405642Y237018D01*
Y192098D01*
X411400Y186340D01*
Y183900D01*
G01X330000Y496213D02*
Y501900D01*
G01X320500Y531000D02*
X321200Y530300D01*
X322501D01*
X324969Y532768D01*
Y538082D01*
X322484Y540567D01*
X314556D01*
X312362Y542761D01*
Y547138D01*
X311500Y548000D01*
G01X321000Y527000D02*
Y527002D01*
X322323Y528325D01*
X323320D01*
X326944Y531949D01*
Y538901D01*
X323303Y542542D01*
X315375D01*
X314337Y543580D01*
Y547437D01*
X314900Y548000D01*
G01X502678Y812181D02*
X495688D01*
X493719Y814150D01*
X481134D01*
X383327Y716343D01*
X331843D01*
X329913Y714413D01*
G01X520178Y812181D02*
X516803D01*
X514747Y814237D01*
X495648D01*
X494310Y815575D01*
X480543D01*
X382736Y717768D01*
X328736D01*
X321500Y710532D01*
Y706500D01*
G01X482000Y811750D02*
X480750D01*
X383918Y714918D01*
X334918D01*
X328331Y708331D01*
G01X302554Y723163D02*
X303448Y722269D01*
X306471D01*
G01X301310Y726403D02*
X301490Y726583D01*
X303614D01*
X306471Y723726D01*
Y722269D01*
G01X417988Y813088D02*
X337581Y732681D01*
X327678D01*
G01D02*
Y731178D01*
X326000Y729500D01*
Y729000D01*
G01X311178Y760181D02*
X315484D01*
X317338Y758327D01*
Y756473D01*
X315959Y755094D01*
Y753863D01*
X315290Y753194D01*
Y753095D01*
X314812Y752617D01*
Y738692D01*
X319156Y734348D01*
Y730943D01*
X318162Y729949D01*
G01X315132Y727197D02*
X315410D01*
X318162Y729949D01*
G01X310406Y723148D02*
Y723499D01*
X313408Y726501D01*
X314436D01*
X315132Y727197D01*
G01X311678Y732681D02*
X313157Y731202D01*
Y728613D01*
X310742Y726198D01*
X307278D01*
G01X317000Y748250D02*
Y750043D01*
X317453Y750496D01*
Y752192D01*
G01X301000Y747750D02*
X304440D01*
X306440Y749750D01*
G01X327678Y736181D02*
X329181D01*
X332500Y739500D01*
G01X327560Y743250D02*
X330250D01*
X332500Y741000D01*
Y739500D01*
G01X311560Y743250D02*
Y736299D01*
X311678Y736181D01*
G01D02*
X313052Y734807D01*
X315531D01*
G01X319406Y767648D02*
X313348D01*
X311200Y765500D01*
G01X362533Y808033D02*
X331380Y776880D01*
X319685D01*
X316167Y773362D01*
X313242D01*
X311406Y775198D01*
G01X302700Y765400D02*
X307062D01*
X307400Y765738D01*
G01X325678Y760181D02*
X322359Y763500D01*
X309638D01*
X307400Y765738D01*
G01X303406Y768648D02*
Y766106D01*
X302700Y765400D01*
G01X323406Y767648D02*
X326481D01*
X327373Y766756D01*
Y765761D01*
G01X315406Y765598D02*
X315808Y766000D01*
X317861D01*
X318001Y765860D01*
X321860D01*
X322795Y764925D01*
X322950D01*
X323875Y764000D01*
X326405D01*
X327373Y764968D01*
Y765761D01*
G01X315406Y775200D02*
X319815Y779609D01*
X328609D01*
X364759Y815759D01*
G01X307406Y775198D02*
X307500Y775292D01*
Y780100D01*
G01D02*
X309400Y778200D01*
Y774605D01*
X312068Y771937D01*
X316758D01*
X319742Y774921D01*
X335921D01*
X360807Y799807D01*
G01X322440Y749750D02*
Y755919D01*
X321678Y756681D01*
G01D02*
X321040D01*
X317453Y753094D01*
Y752192D01*
G01X307178Y756681D02*
X303181D01*
X303000Y756500D01*
G01D02*
Y755940D01*
X306440Y752500D01*
Y749750D01*
G01X325000D02*
Y756003D01*
X325678Y756681D01*
G01D02*
X327227Y758230D01*
X329575D01*
G01X309000Y749750D02*
Y754503D01*
X311178Y756681D01*
G01D02*
X311897Y757400D01*
X315100D01*
G01X359061Y335014D02*
X374400Y319675D01*
Y241700D01*
X370125Y237425D01*
Y198722D01*
X395822Y173025D01*
X403111D01*
X439074Y137062D01*
X460044D01*
X462257Y139275D01*
X479801D01*
X490426Y149900D01*
X522810D01*
X526321Y146389D01*
X558479D01*
X559791Y147701D01*
X560971D01*
X560972Y147700D01*
X570419D01*
X570754Y147365D01*
G01X433000Y169700D02*
X408492Y194208D01*
Y238200D01*
X399792Y246900D01*
Y320920D01*
X399793Y320921D01*
Y356831D01*
X338725Y417899D01*
Y481514D01*
G01D02*
Y488305D01*
X335570Y491460D01*
G01X334800Y712000D02*
X336293Y713493D01*
X384509D01*
X456854Y785838D01*
X478837D01*
X480100Y784575D01*
G01X367000Y704000D02*
X368838D01*
X369263Y703575D01*
X434950D01*
X495307Y763932D01*
G01X360000Y704000D02*
X363275Y700725D01*
X440100D01*
X495824Y756449D01*
G01X344200Y696300D02*
X347550Y692950D01*
X355334D01*
X357535Y690749D01*
X375727D01*
X375728Y690750D01*
X467682D01*
X505432Y728500D01*
X872500D01*
G01X524795Y778529D02*
X524700Y778434D01*
Y764100D01*
X516100Y755500D01*
X509474D01*
X453274Y699300D01*
X362000D01*
X356800Y704500D01*
X354300D01*
G01X887500Y731500D02*
X506416D01*
X467091Y692175D01*
X375137D01*
X375136Y692174D01*
X358126D01*
X354300Y696000D01*
G01X363500Y704000D02*
X365350Y702150D01*
X437458D01*
X487744Y752436D01*
G01X370473Y889470D02*
Y880673D01*
X368500Y878700D01*
Y877316D01*
X372346Y873470D01*
Y817846D01*
X362533Y808033D01*
G01X367323Y889470D02*
Y876477D01*
X370921Y872879D01*
Y821921D01*
X364759Y815759D01*
G01X373622Y889470D02*
Y874210D01*
X373771Y874061D01*
Y812771D01*
X360807Y799807D01*
G01X547173Y167987D02*
Y167973D01*
X544714Y165514D01*
X525539D01*
X521000Y160975D01*
X486156D01*
X486155Y160976D01*
X484975D01*
X477559Y153560D01*
X463279D01*
X459939Y156900D01*
X459187D01*
X459186Y156901D01*
X434904D01*
X407704Y184100D01*
X400862D01*
X383600Y201362D01*
Y203200D01*
G01X370500Y705500D02*
X371000Y705000D01*
X432308D01*
X487949Y760641D01*
G01X427166Y889470D02*
Y869534D01*
X431100Y865600D01*
Y826200D01*
X417988Y813088D01*
G01X465485Y190680D02*
X453600Y202565D01*
Y245705D01*
X478607Y270712D01*
Y311593D01*
X476890Y313310D01*
Y331095D01*
X478875Y333080D01*
Y334975D01*
X552400Y408500D01*
X559900D01*
X567150Y415750D01*
G01X461300Y813100D02*
X460475Y812275D01*
Y809764D01*
X460950Y809289D01*
X464334D01*
X465425Y810380D01*
Y822113D01*
X475722Y832410D01*
X489125D01*
X491083Y830452D01*
Y828226D01*
X491906Y827403D01*
G01X457900Y813100D02*
X458500Y812500D01*
Y808945D01*
X460131Y807314D01*
X465153D01*
X467400Y809561D01*
Y821294D01*
X476541Y830435D01*
X488306D01*
X489108Y829633D01*
Y828605D01*
X487906Y827403D01*
G01X480910Y164099D02*
Y174875D01*
X480032Y175753D01*
Y318163D01*
X482400Y320531D01*
Y335932D01*
X553543Y407075D01*
X564348D01*
X594549Y437276D01*
X1309288D01*
X1323200Y423364D01*
Y349003D01*
X1308534Y334337D01*
X1279163D01*
X1274030Y339470D01*
G01X1280836Y338164D02*
X1283238Y335762D01*
X1307943D01*
X1321775Y349594D01*
Y422773D01*
X1308697Y435851D01*
X595140D01*
X564939Y405650D01*
X554134D01*
X483825Y335341D01*
Y319940D01*
X481457Y317572D01*
Y176344D01*
X482748Y175053D01*
Y162648D01*
X480800Y160700D01*
G01X1295000Y338000D02*
X1308165D01*
X1319352Y349187D01*
Y393447D01*
X1280349Y432450D01*
X593755D01*
X565530Y404225D01*
X558229D01*
X485250Y331246D01*
Y319349D01*
X483057Y317156D01*
Y179843D01*
X486600Y176300D01*
X494400D01*
X498900Y171800D01*
G01X525785Y362796D02*
X497262Y334273D01*
Y281556D01*
X499438Y279380D01*
Y265500D01*
X498624Y264686D01*
Y253324D01*
X488800Y243500D01*
Y207900D01*
X501200Y195500D01*
Y190400D01*
X516000Y175600D01*
X564447D01*
X571316Y168731D01*
X636099D01*
X700226Y104604D01*
Y76474D01*
X715200Y61500D01*
X724716D01*
X732392Y53824D01*
Y49745D01*
X734738Y47399D01*
Y23963D01*
X759701Y-1000D01*
X774497D01*
X781774Y-8277D01*
X824238D01*
X824427Y-8088D01*
X889925D01*
X902388Y4375D01*
Y13737D01*
X901746Y14379D01*
Y17385D01*
X908262Y23901D01*
X959399D01*
X962543Y27045D01*
Y28245D01*
X968986Y34688D01*
X988461D01*
X993653Y39880D01*
X994650D01*
G01X1307500Y340500D02*
X1317927Y350927D01*
Y392856D01*
X1279758Y431025D01*
X594346D01*
X566121Y402800D01*
X558820D01*
X496073Y340053D01*
Y335100D01*
X495837Y334864D01*
Y280965D01*
X496073Y280729D01*
Y253573D01*
X486200Y243700D01*
Y208300D01*
X496073Y198427D01*
Y190642D01*
X503975Y182740D01*
Y172372D01*
G01X480200Y376950D02*
X479273Y376023D01*
Y363869D01*
G01D02*
Y356527D01*
X480000Y355800D01*
G01X479273Y363869D02*
X480533D01*
G01X476200Y376950D02*
X477298Y375852D01*
Y371442D01*
G01D02*
Y356498D01*
X476600Y355800D01*
G01X477298Y371442D02*
X475782D01*
G01X480200Y380450D02*
X479355Y381295D01*
Y388964D01*
G01D02*
Y404593D01*
X480368Y405606D01*
G01X479355Y388964D02*
X480960D01*
G01X476200Y380450D02*
X477380Y381630D01*
Y399971D01*
G01D02*
Y404757D01*
X476531Y405606D01*
G01X477380Y399971D02*
X476010D01*
G01X487906Y775148D02*
X486130D01*
X483856Y777422D01*
X482925D01*
G01X489522Y780127D02*
X489388Y779993D01*
X485724D01*
G01X491906Y775148D02*
Y777743D01*
X489522Y780127D01*
G01X499906Y775148D02*
X500411Y774643D01*
X504169D01*
G01X500778Y781031D02*
Y780098D01*
X504000Y776876D01*
Y774812D01*
X504169Y774643D01*
G01X495307Y763932D02*
X499906Y768531D01*
G01X495824Y756449D02*
X507906Y768531D01*
G01X491900Y784650D02*
X490556D01*
X489415Y783509D01*
X489352D01*
X488505Y782662D01*
X488107D01*
X487907Y782462D01*
X482593D01*
X482550Y782505D01*
X476495D01*
X475000Y784000D01*
X469000D01*
G01X495906Y775148D02*
Y776820D01*
X497910Y778824D01*
G01X487949Y760641D02*
X495906Y768598D01*
G01X503906D02*
X487744Y752436D01*
G01X492500Y811750D02*
X493750D01*
X494582Y810918D01*
Y804000D01*
G01X534678Y812181D02*
X532622Y814237D01*
X516764D01*
X515339Y815662D01*
X496239D01*
X494901Y817000D01*
X482000D01*
X481000Y818000D01*
G01X498000Y804250D02*
Y808500D01*
X498500Y809000D01*
G01X502678Y808681D02*
X502359Y809000D01*
X498500D01*
G01X482000Y808250D02*
X479750D01*
X477000Y805500D01*
Y804000D01*
G01D02*
X480550D01*
X480800Y804250D01*
G01D02*
X483331Y801719D01*
X486662D01*
G01X492500Y808250D02*
X489222Y804972D01*
Y801719D01*
G01D02*
Y800036D01*
X487767Y798581D01*
X483381D01*
X481600Y796800D01*
G01X491782Y795219D02*
X493686D01*
X496000Y792905D01*
Y788000D01*
G01X491900Y788150D02*
X495850D01*
X496000Y788000D01*
G01X495878Y820681D02*
X492459D01*
X492278Y820500D01*
G01X497000Y817500D02*
X496075Y818425D01*
X493575D01*
X492278Y819722D01*
Y820500D01*
G01X500406Y820648D02*
Y817903D01*
X500415Y817894D01*
Y817532D01*
G01X693243Y804943D02*
X658250Y769950D01*
X595482D01*
X533544Y831888D01*
X504488D01*
X500700Y828100D01*
G01X695049Y811349D02*
X658762Y775062D01*
X592386D01*
X534135Y833313D01*
X502621D01*
X500807Y831499D01*
G01X527104Y64292D02*
Y73196D01*
X523900Y76400D01*
Y81419D01*
X526339Y83858D01*
Y86161D01*
X517075Y95425D01*
Y115725D01*
X515220Y117580D01*
Y126440D01*
G01X527104Y79252D02*
Y82607D01*
X527764Y83267D01*
Y86752D01*
X518500Y96016D01*
Y116610D01*
X520910Y119020D01*
Y124390D01*
G01X521820Y130320D02*
X525820D01*
G01X521820D02*
Y125300D01*
X520910Y124390D01*
G01X513820Y130320D02*
X517820D01*
G01D02*
Y129040D01*
X515220Y126440D01*
G01X521820Y133820D02*
X517820D01*
G01X509369Y141559D02*
Y139655D01*
X513820Y135204D01*
Y133820D01*
G01X525820D02*
X529100Y130540D01*
Y125600D01*
X530800Y123900D01*
G01X529176Y151713D02*
X530900Y153437D01*
Y154800D01*
X531900Y155800D01*
G01X532560Y152046D02*
X536769Y156255D01*
X538158D01*
G01X539481Y286676D02*
X530800Y277995D01*
Y258223D01*
X536915Y252108D01*
Y249329D01*
X552460Y233784D01*
X555238D01*
X585603Y203420D01*
X644656D01*
X673150Y174926D01*
X751763D01*
X751871Y175034D01*
G01X529154Y255014D02*
X530515Y253653D01*
Y252228D01*
X551434Y231309D01*
X554212D01*
X584577Y200945D01*
X643630D01*
X672124Y172451D01*
X753073D01*
X763389Y182767D01*
X766731D01*
X768414Y184450D01*
Y187194D01*
X770385Y189165D01*
G01X529881Y287376D02*
X524000Y281495D01*
Y260168D01*
X529154Y255014D01*
G01X532978Y371023D02*
Y369989D01*
X525785Y362796D01*
G01X534500Y395100D02*
X539950Y400550D01*
X540150D01*
X556675Y417075D01*
X562464D01*
X589003Y443614D01*
X1316997D01*
X1384842Y375769D01*
Y187716D01*
X1388078Y184480D01*
Y179437D01*
X1384842Y176201D01*
Y170430D01*
X1385402Y169870D01*
Y166751D01*
X1382179Y163528D01*
X1379473D01*
G01X1387196Y174160D02*
X1389513Y176477D01*
Y186503D01*
X1387926Y188090D01*
X1387925Y374702D01*
X1317588Y445039D01*
X588412D01*
X561873Y418500D01*
X552600D01*
X528850Y394750D01*
G01X521900Y774850D02*
X521150D01*
X518328Y777672D01*
Y781467D01*
G01X515278Y779198D02*
X517547Y781467D01*
X518328D01*
G01X507729Y778198D02*
Y779001D01*
X513473Y784745D01*
X514298D01*
G01X507729Y778198D02*
X507657Y778126D01*
Y775525D01*
X508232Y774950D01*
X509600D01*
G01D02*
X513700D01*
G01X506950Y788700D02*
X505600Y787350D01*
Y780520D01*
X504278Y779198D01*
G01X524178Y812181D02*
X524881D01*
X525512Y812812D01*
X530688D01*
X531900Y811600D01*
Y808400D01*
X526548Y803048D01*
Y793035D01*
X528812Y790771D01*
X529493D01*
X532632Y787632D01*
Y779732D01*
X531500Y778600D01*
G01X528179Y782555D02*
X529289Y781445D01*
Y779901D01*
X530590Y778600D01*
X531500D01*
G01X527000Y774950D02*
Y781376D01*
X528179Y782555D01*
G01X524678Y784681D02*
Y784125D01*
X524688Y784115D01*
Y782938D01*
X524689Y782937D01*
Y778635D01*
X524795Y778529D01*
G01X517800Y774950D02*
X517450D01*
X515400Y777000D01*
X512999D01*
X511484Y778515D01*
G01X506678Y812181D02*
X507309Y812812D01*
X513000D01*
X513338Y812474D01*
Y801781D01*
X510698Y799141D01*
Y793702D01*
X512812Y791588D01*
Y786231D01*
X514298Y784745D01*
G01X516943Y817401D02*
X518682Y815662D01*
X532500D01*
X533838Y817000D01*
X537500D01*
G01X503440Y801750D02*
Y805060D01*
X502678Y805822D01*
Y808681D01*
G01X520178D02*
X517181D01*
X516500Y808000D01*
G01D02*
Y807440D01*
X519440Y804500D01*
Y801750D01*
G01X514000Y799250D02*
X515250D01*
X517750Y801750D01*
X519440D01*
G01X530000Y799250D02*
X530012Y799262D01*
Y803025D01*
G01X535440Y801750D02*
Y805738D01*
X534678Y806500D01*
Y808681D01*
G01D02*
X530012Y804015D01*
Y803025D01*
G01X506000Y801750D02*
Y804500D01*
X507000Y805500D01*
X509000D01*
X510500Y807000D01*
Y808500D01*
G01X506678Y808681D02*
X507497Y809500D01*
X509500D01*
X510500Y808500D01*
G01X522000Y801750D02*
Y806503D01*
X524178Y808681D01*
G01D02*
X525117Y809620D01*
X527948D01*
G01X508560Y795250D02*
Y791900D01*
X510450Y790010D01*
Y788700D01*
G01D02*
Y786450D01*
X508700Y784700D01*
G01X524560Y795250D02*
Y788299D01*
X524678Y788181D01*
G01D02*
X524859Y788000D01*
X528500D01*
G01X524906Y820648D02*
X521648D01*
X521000Y820000D01*
G01X524700Y817500D02*
X522000D01*
X521000Y818500D01*
Y820000D01*
G01X508579Y820600D02*
X504563D01*
X504241Y820278D01*
G01X507044Y817569D02*
X505431D01*
X504241Y818759D01*
Y820278D01*
G01X691487Y798987D02*
X661024Y768524D01*
X594892D01*
X532953Y830463D01*
X511621D01*
X508579Y827421D01*
G01X516906Y820648D02*
Y817438D01*
X516943Y817401D01*
G01X532678Y889470D02*
Y841378D01*
X527500Y836200D01*
G01X528906Y820648D02*
X531858D01*
X532506Y820000D01*
G01X528906Y817598D02*
X529004Y817500D01*
X532000D01*
X532506Y818006D01*
Y820000D01*
G01X512679Y820600D02*
Y818079D01*
X512672Y818072D01*
Y817624D01*
X512716Y817580D01*
Y817550D01*
G01X688212Y791912D02*
X663399Y767099D01*
X593633D01*
X531694Y829038D01*
X514217D01*
X512679Y827500D01*
G01X570411Y64292D02*
Y71589D01*
X568000Y74000D01*
Y81000D01*
X569646Y82646D01*
Y87354D01*
X566499Y90501D01*
X566483D01*
X560925Y96059D01*
Y105651D01*
X573055Y117781D01*
Y121869D01*
G01X570411Y79252D02*
Y81395D01*
X571071Y82055D01*
Y87945D01*
X567090Y91926D01*
X567074D01*
X562350Y96650D01*
Y105060D01*
X577336Y120046D01*
Y125424D01*
G01X566531Y143123D02*
Y142064D01*
X566615Y141980D01*
Y141475D01*
X570345Y137745D01*
Y133780D01*
G01X731800Y166000D02*
X670193D01*
X641844Y194349D01*
X578134D01*
X556960Y215523D01*
X556299D01*
X546610Y225212D01*
X544588D01*
X540944Y228856D01*
X539798D01*
G01X539934Y232660D02*
X545407Y227187D01*
X547466D01*
X547729Y226924D01*
X548353D01*
X578953Y196324D01*
X642663D01*
X670749Y168238D01*
X691100D01*
G01X773984Y189118D02*
Y185904D01*
X768001Y179921D01*
X763337D01*
X753892Y170476D01*
X671305D01*
X643482Y198299D01*
X579772D01*
X549172Y228899D01*
X548919D01*
X548656Y229162D01*
G01X1255000Y323000D02*
Y339600D01*
X1259398Y343998D01*
Y401632D01*
X1237305Y423725D01*
X604326D01*
X550882Y370281D01*
Y304618D01*
X555801Y299699D01*
Y250511D01*
X569912Y236400D01*
X573300D01*
X575200Y234500D01*
X576100D01*
G01X763562Y189539D02*
X762262Y188239D01*
X761575D01*
X750737Y177401D01*
X674245D01*
X645751Y205895D01*
X590031D01*
X582131Y213795D01*
X580111D01*
X567369Y226537D01*
Y226589D01*
X557698Y236260D01*
X553485D01*
X539390Y250355D01*
Y275749D01*
X544993Y281352D01*
G01X548656Y229162D02*
X547167D01*
X540035Y236294D01*
G01X660700Y212000D02*
X659544D01*
X657338Y214206D01*
Y214261D01*
X656261Y215338D01*
X642840D01*
X641972Y214470D01*
X635102D01*
X630952Y218620D01*
X582112D01*
X572196Y228536D01*
Y232100D01*
X553219Y251077D01*
Y299581D01*
X548075Y304725D01*
Y381674D01*
X563326Y396925D01*
X573325D01*
X603150Y426750D01*
X1270428D01*
X1312839Y384339D01*
G01X1305500Y379500D02*
X1311165D01*
X1315077Y383412D01*
Y391674D01*
X1278576Y428175D01*
X602559D01*
X572734Y398350D01*
X562735D01*
X546650Y382265D01*
Y303950D01*
X551794Y298806D01*
Y250486D01*
X570771Y231509D01*
Y227945D01*
X581521Y217195D01*
X630361D01*
X634511Y213045D01*
X652385D01*
X653609Y211821D01*
X653610D01*
X655669Y209762D01*
X667517D01*
X670363Y212608D01*
X671885D01*
X672493Y212000D01*
X674500D01*
G01X687900Y208100D02*
X687663Y208337D01*
X655077D01*
X651794Y211620D01*
X633920D01*
X629770Y215770D01*
X580930D01*
X569345Y227355D01*
Y230919D01*
X550369Y249895D01*
Y297931D01*
X545225Y303075D01*
Y382856D01*
X562144Y399775D01*
X572143D01*
X601968Y429600D01*
X1279167D01*
X1316502Y392265D01*
Y382821D01*
X1310181Y376500D01*
X1298500D01*
G01X541637Y263240D02*
X542818Y264421D01*
Y269927D01*
X546969Y274078D01*
Y296331D01*
X541825Y301475D01*
Y374019D01*
X539400Y376444D01*
G01X545974Y263240D02*
X544793Y264421D01*
Y269108D01*
X548944Y273259D01*
Y297150D01*
X543800Y302294D01*
Y374838D01*
X540581Y378057D01*
Y379600D01*
X539400Y380781D01*
G01X560531Y364830D02*
Y368731D01*
X561300Y369500D01*
G01X561912Y390762D02*
X562276Y390398D01*
X568814D01*
X603741Y425325D01*
X1258085D01*
X1273500Y409910D01*
Y406500D01*
G01X1364000Y299500D02*
Y394595D01*
X1316406Y442189D01*
X593093Y442188D01*
X589593D01*
X563055Y415650D01*
X562850D01*
X560900Y413700D01*
G01X540500Y781000D02*
X544500D01*
X545500Y782000D01*
Y783500D01*
G01X537500Y817000D02*
X538678Y815822D01*
Y812181D01*
G01X542800Y812550D02*
X542431Y812181D01*
X538678D01*
G01X540678Y784681D02*
X544319D01*
X545500Y783500D01*
G01X538678Y808681D02*
Y806500D01*
X538000Y805822D01*
Y801750D01*
G01D02*
Y799499D01*
X539111Y798388D01*
X544788D01*
X546200Y799800D01*
G01X540560Y795250D02*
X543750D01*
X546000Y793000D01*
G01X540678Y788181D02*
X544181D01*
X546000Y790000D01*
Y793000D01*
G01X578467Y130280D02*
X577336Y129149D01*
Y125424D01*
G01X578467Y130280D02*
X582467D01*
G01X574345D02*
X570345D01*
G01X573055Y121869D02*
Y125276D01*
X575866Y128087D01*
Y128759D01*
X574345Y130280D01*
G01Y133780D02*
X578467D01*
G01X582467D02*
X581600Y134647D01*
Y142101D01*
X576336Y147365D01*
X570754D01*
G01X613718Y64292D02*
Y72282D01*
X611530Y74470D01*
Y82434D01*
X612954Y83858D01*
Y87956D01*
X605725Y95185D01*
Y108253D01*
X611642Y114170D01*
Y123340D01*
G01X613718Y79252D02*
Y82606D01*
X614379Y83267D01*
Y88547D01*
X607150Y95776D01*
Y107662D01*
X616614Y117126D01*
Y123871D01*
G01X610766Y84764D02*
Y88034D01*
X604300Y94500D01*
Y109140D01*
X609358Y114198D01*
Y126497D01*
X610073Y127212D01*
Y142727D01*
X609122Y143678D01*
Y147811D01*
X607812Y149121D01*
G01X620048Y130494D02*
X624048D01*
G01X620048D02*
X616614Y127060D01*
Y123871D01*
G01X612026Y130502D02*
X616026D01*
G01X611642Y123340D02*
Y130118D01*
X612026Y130502D01*
G01X616026Y134002D02*
Y135734D01*
X616559Y136267D01*
Y139325D01*
X611097Y144787D01*
Y147369D01*
X612812Y149084D01*
G01X616026Y134002D02*
X620040D01*
X620048Y133994D01*
G01X624048D02*
X623345D01*
X619090Y138249D01*
Y140950D01*
X616900Y143140D01*
Y144450D01*
X616950Y144500D01*
X617000D01*
G01X612026Y134002D02*
Y135389D01*
X614721Y138084D01*
Y138287D01*
G01X609777Y158860D02*
X615500Y153137D01*
Y146300D01*
X617000Y144800D01*
Y144500D01*
G01X1198134Y420766D02*
X1196600Y422300D01*
X605500D01*
X604400Y421200D01*
G01X1179723Y418777D02*
X1178200Y420300D01*
X615700D01*
X615500Y420100D01*
G01X636615Y889470D02*
Y856085D01*
X641000Y851700D01*
Y816500D01*
G01X657025Y64292D02*
Y71475D01*
X654837Y73663D01*
Y82434D01*
X656261Y83858D01*
Y85670D01*
X649692Y92239D01*
Y125160D01*
G01X657025Y79252D02*
Y82606D01*
X657686Y83267D01*
Y86261D01*
X651117Y92830D01*
Y120767D01*
X655000Y124650D01*
Y125360D01*
G01X654073Y84764D02*
X648267Y90570D01*
Y120708D01*
X643518Y125457D01*
G01X655000Y130250D02*
Y125360D01*
G01Y130250D02*
X659500D01*
G01X650500D02*
X649692Y129442D01*
Y125160D01*
G01X650500Y130250D02*
X646000D01*
G01Y133750D02*
X645610Y134140D01*
Y141610D01*
X647000Y143000D01*
G01X656500Y139300D02*
X659500Y136300D01*
Y133750D01*
G01X654500Y143000D02*
Y141300D01*
X656500Y139300D01*
G01X650500Y133750D02*
X655000D01*
G01X645800Y780500D02*
Y781100D01*
X643538Y783362D01*
Y803500D01*
G01X645800Y776900D02*
X641000Y781700D01*
Y816500D01*
G01X639764Y889470D02*
Y880302D01*
X639075Y879613D01*
Y855641D01*
X643538Y851178D01*
Y803500D01*
G01X642914Y889470D02*
Y882214D01*
X640462Y879762D01*
Y877180D01*
X640500Y877142D01*
Y870014D01*
X642914Y867600D01*
Y853818D01*
X646800Y849932D01*
Y811500D01*
G01X645800Y783900D02*
X646800Y784900D01*
Y788200D01*
G01D02*
Y811500D01*
G01X803265Y174050D02*
X798250Y169035D01*
X782404D01*
X775769Y175670D01*
X761880D01*
X754448Y168238D01*
X691100D01*
G01X714900Y818600D02*
X711100D01*
X691487Y798987D01*
G01X724804Y889470D02*
Y880134D01*
X725875Y879063D01*
Y875225D01*
X727200Y873900D01*
Y838900D01*
X693243Y804943D01*
G01X712495Y816195D02*
X688212Y791912D01*
G01X695049Y811349D02*
X701000Y817300D01*
G01D02*
X724450Y840750D01*
Y871700D01*
X724738Y871988D01*
Y878962D01*
X721654Y882046D01*
Y889470D01*
G01X715380Y22030D02*
Y18000D01*
X715300Y17920D01*
G01X711510Y13930D02*
Y14130D01*
X715300Y17920D01*
G01X715613Y37236D02*
X715130Y37719D01*
Y45650D01*
G01X720100Y38050D02*
X718215D01*
X717401Y37236D01*
X715613D01*
G01X715390Y33130D02*
X715830D01*
X718500Y35800D01*
X720835D01*
X721938Y36903D01*
X728343D01*
X732900Y41460D01*
Y44900D01*
G01X730021Y42235D02*
X729975D01*
X729500Y42710D01*
Y54700D01*
X726300Y57900D01*
X716380D01*
X715130Y56650D01*
G01X731800Y166000D02*
X755152D01*
X762661Y173509D01*
X774920D01*
X781578Y166851D01*
X799466D01*
X806665Y174050D01*
G01X741600Y41000D02*
Y34439D01*
G01D02*
Y21897D01*
X752697Y10800D01*
X767755D01*
X771715Y6840D01*
G01X816043Y94981D02*
X814862Y96162D01*
X796644D01*
X762343Y130463D01*
Y168141D01*
X761242Y169242D01*
G01X765579D02*
X764318Y167981D01*
Y131282D01*
X797463Y98137D01*
X814862D01*
X816043Y99318D01*
G01X768777Y171450D02*
Y163607D01*
X829500Y102884D01*
Y79889D01*
X845113Y64276D01*
X862876D01*
X866362Y67762D01*
X919262D01*
X922100Y70600D01*
X939900D01*
X946776Y63724D01*
X952623D01*
X959147Y57200D01*
X983282D01*
X988548Y51934D01*
Y48851D01*
X989699Y47700D01*
X993345D01*
X994609Y48964D01*
Y50486D01*
X995686Y51563D01*
X1010138D01*
X1010539Y51162D01*
X1012061D01*
X1012462Y51563D01*
X1016587D01*
X1024432Y43718D01*
G01X766950Y189252D02*
X762994Y185296D01*
X762133D01*
X751871Y175034D01*
G01X790150Y-1400D02*
Y3434D01*
X801100Y14384D01*
Y17400D01*
X815976Y32276D01*
G01X811937Y41381D02*
X799675Y29119D01*
Y14975D01*
X787600Y2900D01*
Y-3513D01*
X788408Y-4321D01*
G01X892178Y789181D02*
X892128D01*
X888859Y792450D01*
X885610D01*
X883200Y794860D01*
X874100D01*
X871890Y792650D01*
X864610D01*
X862912Y794348D01*
X821632D01*
X799459Y772175D01*
G01X807514Y2199D02*
Y13310D01*
X808838Y14634D01*
Y21733D01*
X827727Y40622D01*
Y43554D01*
G01X815976Y32276D02*
X823600Y39900D01*
Y43880D01*
X823996Y44276D01*
G01X838252Y20800D02*
X838787Y21335D01*
Y27101D01*
X838881Y27195D01*
G01X838252Y17750D02*
Y20800D01*
G01X834252Y17750D02*
Y20552D01*
X834500Y20800D01*
G01X830500D02*
X830478Y20822D01*
Y22889D01*
X831152Y23563D01*
Y23634D01*
X832259Y24741D01*
X833246D01*
G01X830252Y17750D02*
X831551D01*
X832390Y18589D01*
Y21289D01*
X833279Y22178D01*
Y24708D01*
X833246Y24741D01*
G01X828283Y24734D02*
Y23736D01*
X826141Y21594D01*
G01D02*
X826146Y21589D01*
Y17062D01*
X826138Y17054D01*
G01X819052Y23633D02*
X818500Y23081D01*
Y19221D01*
X820052Y17669D01*
X820212D01*
G01X824462Y25770D02*
X823730Y26502D01*
X821921D01*
X819052Y23633D01*
G01X820004Y44234D02*
X819581Y43811D01*
X814367D01*
X811937Y41381D01*
G01X827727Y43554D02*
Y47827D01*
X828700Y48800D01*
G01X990628Y49698D02*
X990091Y50235D01*
Y53093D01*
X984559Y58625D01*
X959738D01*
X958017Y60346D01*
Y61799D01*
X954666Y65150D01*
X947366D01*
X940491Y72025D01*
X921509D01*
X918709Y69225D01*
X865809D01*
X862285Y65701D01*
X845704D01*
X839000Y72405D01*
Y82100D01*
X844550Y87650D01*
X848100D01*
G01X817405Y779905D02*
X828998Y791498D01*
X853912D01*
X855190Y790220D01*
G01X878600Y788750D02*
X876712D01*
X874242Y791220D01*
X864024D01*
X862321Y792923D01*
X824923D01*
X808584Y776584D01*
G01X837000Y774750D02*
X831500D01*
G01X836300Y783300D02*
Y778950D01*
X837000Y778250D01*
G01X836300Y783300D02*
X836400Y783400D01*
X838100D01*
X841000Y780500D01*
Y778250D01*
G01X816142Y889470D02*
Y837858D01*
X839500Y814500D01*
X864000D01*
G01X819292Y889470D02*
Y882992D01*
X818000Y881700D01*
Y873792D01*
X819292Y872500D01*
Y837208D01*
X839138Y817362D01*
X853500D01*
G01X825591Y889470D02*
Y835046D01*
X837299Y823338D01*
X863500D01*
G01X822441Y889470D02*
Y836180D01*
X838121Y820500D01*
X845500D01*
G01X861000Y350D02*
X863550D01*
X865600Y-1700D01*
G01X857453Y303D02*
X855903D01*
X853500Y-2100D01*
G01X849051Y20908D02*
X850708D01*
X853100Y23300D01*
X858800D01*
X863500Y28000D01*
G01X873100Y30750D02*
X870911Y28561D01*
X864061D01*
X863500Y28000D01*
G01X877300Y30750D02*
X873100D01*
G01D02*
X873060Y30790D01*
Y37350D01*
G01X845052Y20800D02*
Y21495D01*
X848519Y24962D01*
X848520Y24961D01*
X848545D01*
G01X846252Y17750D02*
Y19848D01*
X845300Y20800D01*
X845052D01*
G01X841652D02*
X843545Y22693D01*
Y25012D01*
G01X842252Y17750D02*
Y19948D01*
X841652Y20548D01*
Y20800D01*
G01X870600Y18915D02*
Y16509D01*
X871800Y15309D01*
G01X870500Y37350D02*
Y39700D01*
X871512Y40712D01*
X878888D01*
X883500Y36100D01*
G01X856650Y16200D02*
X850900D01*
G01D02*
Y17448D01*
X854252Y20800D01*
G01X848623Y74557D02*
Y70757D01*
G01X852019Y70589D02*
Y76708D01*
X859000Y83689D01*
Y86500D01*
G01X855421Y70551D02*
Y78094D01*
X862000Y84673D01*
Y87500D01*
X866919Y92419D01*
G01X858821Y75500D02*
Y70614D01*
G01X867940Y43850D02*
X866150D01*
X864900Y45100D01*
Y49275D01*
X865004Y49379D01*
G01X868800Y49200D02*
X867600Y50400D01*
X866025D01*
X865004Y49379D01*
G01X888500Y93250D02*
X883862Y97888D01*
X864754D01*
X855897Y89031D01*
Y82602D01*
X848623Y75328D01*
Y74557D01*
G01X884000Y93250D02*
Y94700D01*
X882237Y96463D01*
X866963D01*
X859000Y88500D01*
Y86500D01*
G01X879500Y93250D02*
Y93600D01*
X878062Y95038D01*
X869538D01*
X866919Y92419D01*
G01X875000Y93250D02*
X872593D01*
X858821Y79478D01*
Y75500D01*
G01X871000Y82250D02*
X869829Y81079D01*
X867421D01*
X866000Y82500D01*
G01D02*
Y83200D01*
X868100Y85300D01*
X868800D01*
G01X852400Y87550D02*
X852300Y87650D01*
X848100D01*
G01X852400Y87550D02*
X869520Y104670D01*
X875070D01*
G01X875000Y89750D02*
Y89220D01*
X872862Y87082D01*
X871696D01*
G01X875000Y82250D02*
Y83334D01*
X871696Y86638D01*
Y87082D01*
G01X864800Y707700D02*
X865568Y706932D01*
Y637159D01*
X892127Y610600D01*
X1262338D01*
X1263989Y612251D01*
X1273235D01*
X1294977Y633993D01*
Y645191D01*
G01X1293002Y637751D02*
Y634812D01*
X1272416Y614226D01*
X1263170D01*
X1261519Y612575D01*
X892946D01*
X867543Y637978D01*
Y707043D01*
X868200Y707700D01*
G01X895800Y738400D02*
X894600Y737200D01*
X856900D01*
X850799Y743301D01*
G01X854049Y757573D02*
X852873D01*
X848600Y753300D01*
Y745500D01*
X850799Y743301D01*
G01X857087Y889470D02*
Y883787D01*
X854000Y880700D01*
Y873087D01*
X857087Y870000D01*
Y842029D01*
X871891Y827225D01*
X898391D01*
X910900Y814716D01*
Y733500D01*
X905900Y728500D01*
X872500D01*
G01X896500Y734000D02*
X854000D01*
X844500Y743500D01*
Y750000D01*
G01X857406Y755198D02*
X853698D01*
X851500Y753000D01*
G01X856906Y752148D02*
X852352D01*
X851500Y753000D01*
G01X860906Y752148D02*
Y754698D01*
X861406Y755198D01*
G01X872617Y750235D02*
X872172Y750680D01*
X870374D01*
X868906Y752148D01*
G01D02*
X869620Y752862D01*
Y758299D01*
X869517Y758402D01*
Y758412D01*
X869562Y758457D01*
G01X844500Y758000D02*
Y750000D01*
G01X852400Y762150D02*
Y760400D01*
X849500Y757500D01*
X845000D01*
X844500Y758000D01*
G01X866310Y788880D02*
X868100Y787090D01*
Y783500D01*
X872838Y778762D01*
Y775739D01*
X871812Y774713D01*
Y768793D01*
X872039Y768566D01*
Y761936D01*
X872901Y761074D01*
Y756155D01*
X873487Y755569D01*
X875948D01*
X876036Y755481D01*
G01X870150Y765800D02*
Y761795D01*
X871417Y760528D01*
Y753787D01*
X872513Y752691D01*
X873700D01*
X875012Y751379D01*
Y746988D01*
X877000Y745000D01*
G01X864906Y752148D02*
X864366Y752688D01*
Y758100D01*
G01X867410Y755824D02*
X865134Y758100D01*
X864366D01*
G01X841000Y778250D02*
X843350D01*
X844319Y779219D01*
X846662D01*
G01X857500Y781750D02*
X858120Y781130D01*
X859480D01*
X861860Y778750D01*
X862940D01*
G01X857500Y781750D02*
Y785660D01*
X858020Y786180D01*
G01X849222Y779219D02*
Y781708D01*
X845090Y785840D01*
X844810D01*
G01X865500Y778750D02*
Y783740D01*
X864147Y785093D01*
G01X852400Y765650D02*
X854455D01*
X856576Y767771D01*
G01X851782Y772719D02*
X852669Y771832D01*
Y771678D01*
X856576Y767771D01*
G01X868060Y772250D02*
Y769200D01*
X866650Y767790D01*
Y765800D01*
G01D02*
Y762870D01*
X867640Y761880D01*
G01X865378Y797681D02*
X862181D01*
X861500Y797000D01*
G01X866878Y794531D02*
X865195D01*
X863724Y796002D01*
X862498D01*
X861500Y797000D01*
G01X869906Y797648D02*
Y794903D01*
X870278Y794531D01*
G01X839990Y789230D02*
X844700D01*
X844810Y789340D01*
G01X864000Y814500D02*
X881100D01*
X883180Y812420D01*
X895120D01*
X898700Y816000D01*
G01X858020Y786180D02*
X858690Y786850D01*
Y790220D01*
G01X870400Y789150D02*
X872450D01*
X874800Y786800D01*
G01X840960Y785260D02*
X844230D01*
X844810Y785840D01*
G01X862810Y788880D02*
Y786430D01*
X864147Y785093D01*
G01X894406Y818000D02*
X893768Y817362D01*
X888680D01*
X887362Y818680D01*
X868978D01*
X867660Y817362D01*
X853500D01*
G01X888100Y823338D02*
X863500D01*
G01X853937Y889470D02*
Y883137D01*
X852500Y881700D01*
Y872571D01*
X853937Y871134D01*
Y843163D01*
X871300Y825800D01*
X897800D01*
X909400Y814200D01*
Y734600D01*
X906300Y731500D01*
X887500D01*
G01X890200Y819200D02*
X888900Y820500D01*
X845500D01*
G01X878320Y4350D02*
X878332Y4338D01*
X879662D01*
X881700Y2300D01*
G01X883500Y36100D02*
Y32000D01*
X885000Y30500D01*
X888200D01*
G01D02*
X892500D01*
X893100Y31100D01*
Y34650D01*
G01X905488Y48573D02*
Y38665D01*
X918284Y25869D01*
X958768D01*
X959877Y26978D01*
G01X879500Y44900D02*
X876962Y47438D01*
Y50361D01*
X881152Y54551D01*
X882429D01*
G01X883800Y41400D02*
Y46638D01*
X885538Y48376D01*
Y51962D01*
X882949Y54551D01*
X882429D01*
G01X905488Y54479D02*
Y48573D01*
G01X906500Y93250D02*
X915926Y102676D01*
G01X908676Y99926D02*
X902000Y93250D01*
G01X920066Y116388D02*
Y114481D01*
X906700Y101115D01*
X905365D01*
X902169Y97919D01*
G01X897500Y93250D02*
X902169Y97919D01*
G01X918981Y117319D02*
X917700Y116038D01*
Y114131D01*
X906109Y102540D01*
X896140D01*
X894533Y100933D01*
G01X893000Y93250D02*
Y99400D01*
X894533Y100933D01*
G01X875070Y104670D02*
X900779D01*
X905180Y109071D01*
G01X884000Y89750D02*
X881750Y87500D01*
X880000D01*
X878394Y85894D01*
Y85780D01*
G01X884000Y82250D02*
X882693D01*
X879163Y85780D01*
X878394D01*
G01X879500Y89750D02*
X879208D01*
X875461Y86003D01*
X875001D01*
G01X879500Y82250D02*
X878650D01*
X875445Y85455D01*
Y85559D01*
X875001Y86003D01*
G01X906500Y89750D02*
X905707D01*
X901899Y85942D01*
G01X906500Y82250D02*
X905550D01*
Y82291D01*
X901899Y85942D01*
G01X897500Y89750D02*
X893050Y85300D01*
G01D02*
X892900D01*
G01X897500Y82250D02*
X896350D01*
X893300Y85300D01*
X893050D01*
G01X888500Y89750D02*
Y88750D01*
X885042Y85292D01*
G01X888500Y82250D02*
X888084D01*
X885042Y85292D01*
G01X893000Y82250D02*
X889550Y85700D01*
X888950D01*
G01D02*
X888600D01*
G01X893000Y89750D02*
X888950Y85700D01*
G01X897600Y85500D02*
X897750D01*
G01D02*
X902000Y89750D01*
G01Y82250D02*
X901000D01*
X897750Y85500D01*
G01X903920Y137780D02*
Y140060D01*
X901969Y142011D01*
Y143701D01*
G01X902150Y112500D02*
X900000D01*
X898000Y114500D01*
Y117000D01*
G01X901969Y147638D02*
Y147634D01*
X903937Y145666D01*
G01X908020Y153340D02*
X907671D01*
X905906Y151575D01*
G01X903970Y157478D02*
Y153576D01*
X901969Y151575D01*
G01X960500Y607000D02*
X960016D01*
X958178Y605162D01*
X889338D01*
X880889Y613611D01*
G01X953500Y607000D02*
X892000D01*
X875252Y623748D01*
G01X1028741Y889470D02*
Y838307D01*
X1022100Y831666D01*
Y641616D01*
X1004209Y623725D01*
X900275D01*
X896000Y628000D01*
Y686000D01*
G01X1063386Y889470D02*
Y882314D01*
X1066649Y879051D01*
Y870167D01*
X1026475Y829993D01*
Y639943D01*
X1005982Y619450D01*
X898502D01*
X884700Y633252D01*
Y708000D01*
G01X1057087Y889470D02*
Y880398D01*
X1056048Y879359D01*
Y863598D01*
X1023525Y831075D01*
Y641025D01*
X1004800Y622300D01*
X899684D01*
X892100Y629884D01*
Y694000D01*
G01X1066536Y889470D02*
Y880402D01*
X1068074Y878864D01*
Y869576D01*
X1027900Y829402D01*
Y639352D01*
X1006573Y618025D01*
X897911D01*
X881200Y634736D01*
Y713500D01*
G01X1060237Y889470D02*
Y882310D01*
X1056923Y878996D01*
Y874841D01*
X1057473Y874291D01*
Y863007D01*
X1024950Y830484D01*
Y679387D01*
X1024951Y679386D01*
Y678206D01*
X1024950Y678205D01*
Y640434D01*
X1005391Y620875D01*
X899093D01*
X888550Y631418D01*
Y702000D01*
G01X884700Y708000D02*
Y721100D01*
G01X892100Y694000D02*
Y721100D01*
G01X881200Y721300D02*
Y713500D01*
G01X888400Y721400D02*
X888550Y721250D01*
Y702000D01*
G01X877000Y745000D02*
X879704Y742296D01*
X879815D01*
G01X884778Y756198D02*
Y757478D01*
X886800Y759500D01*
G01X889306Y752148D02*
X886800Y754654D01*
Y759500D01*
G01X900050Y765400D02*
X905500Y770850D01*
Y801000D01*
X902600Y803900D01*
Y816300D01*
X895900Y823000D01*
X888438D01*
X888100Y823338D01*
G01X881306Y752148D02*
Y755055D01*
X881300Y755061D01*
Y755871D01*
X880148Y757023D01*
Y759480D01*
X878578Y761050D01*
G01X876036Y755481D02*
X877441Y756886D01*
Y759913D01*
X878578Y761050D01*
G01X877200Y752050D02*
X877206Y752056D01*
Y754311D01*
X876036Y755481D01*
G01X893406Y752148D02*
X898948D01*
X899800Y753000D01*
G01X893406Y752148D02*
Y752709D01*
X894465Y753768D01*
Y755501D01*
G01D02*
X890463Y759503D01*
Y761018D01*
X889500Y761981D01*
Y765214D01*
X887712Y767002D01*
Y768693D01*
X887312Y769093D01*
Y775458D01*
X885312Y777458D01*
Y789558D01*
X881960Y792910D01*
G01X882203Y762245D02*
X887220D01*
X889038Y760427D01*
Y757659D01*
X891056Y755641D01*
G01X885306Y752148D02*
Y753071D01*
X882725Y755652D01*
Y758225D01*
X882229Y758721D01*
Y758835D01*
X882227D01*
G01X892178Y785681D02*
X892940Y784919D01*
Y778750D01*
G01X878600Y785250D02*
Y783620D01*
X876940Y781960D01*
Y778750D01*
G01X895500D02*
Y781500D01*
X896500Y782500D01*
X898500D01*
X900000Y784000D01*
Y786000D01*
G01X882590Y787130D02*
Y783990D01*
X879500Y780900D01*
Y778750D01*
G01X898566Y761430D02*
X896550Y763446D01*
Y765400D01*
G01D02*
X898060Y766910D01*
Y772250D01*
G01X882060D02*
X884250D01*
X885887Y770613D01*
Y766811D01*
X886500Y766198D01*
Y765000D01*
G01X882203Y765745D02*
X884043D01*
X884788Y765000D01*
X886500D01*
G01X894406Y797648D02*
Y794706D01*
X894200Y794500D01*
G01X877949Y800210D02*
X875529D01*
X874033Y798714D01*
Y797475D01*
G01X877930Y796880D02*
X875182D01*
X875181Y796879D01*
X874509D01*
X874033Y797355D01*
Y797475D01*
G01X890500Y796638D02*
Y799783D01*
X890025Y800258D01*
X886276D01*
G01X896178Y789181D02*
X894390Y790969D01*
X893453D01*
X890500Y793922D01*
Y796638D01*
G01X886288Y794372D02*
X886090Y794570D01*
Y800072D01*
X886276Y800258D01*
G01X898406Y797648D02*
Y794494D01*
X898700Y794200D01*
G01X882290Y796770D02*
X882049Y797011D01*
Y800210D01*
G01X887500Y784750D02*
Y788500D01*
X888000Y789000D01*
G01X892178Y785681D02*
X888859Y789000D01*
X888000D01*
G01X874800Y786800D02*
X876350Y785250D01*
X878600D01*
G01X896178Y785681D02*
X896497Y786000D01*
X900000D01*
G01X878460Y792910D02*
X882590Y788780D01*
Y787130D01*
G01X910945Y49234D02*
X909797Y48086D01*
Y36372D01*
X918601Y27568D01*
X950333D01*
X958878Y36113D01*
X987870D01*
X989938Y38181D01*
Y42746D01*
X990312Y43120D01*
X997845D01*
X1004292Y49567D01*
X1015951D01*
X1019701Y45817D01*
Y45590D01*
X1023599Y41692D01*
X1026075D01*
X1030247Y45864D01*
X1035608D01*
X1036854Y47110D01*
G01X910945Y49234D02*
Y53889D01*
X909797Y55037D01*
G01X915315Y97565D02*
X911000Y93250D01*
G01X929000Y121667D02*
X930333D01*
X931500Y120500D01*
Y110069D01*
X933069Y108500D01*
Y105331D01*
X930738Y103000D01*
X929496D01*
X928946Y102450D01*
X920200D01*
X915315Y97565D01*
G01X938000Y93250D02*
X939405D01*
X941593Y95438D01*
X944261D01*
X946438Y97615D01*
Y104553D01*
X947562Y105677D01*
Y113872D01*
X949395Y115705D01*
Y127770D01*
X949212Y127953D01*
G01X924500Y93250D02*
X926312Y95062D01*
X927861D01*
X936555Y103756D01*
Y109726D01*
X940051Y113222D01*
G01X949212Y155512D02*
X946749Y153049D01*
Y142631D01*
X944527Y140409D01*
Y129017D01*
X943802Y128292D01*
Y125915D01*
X944953Y124764D01*
Y120154D01*
X943802Y119003D01*
Y115121D01*
X943490Y114809D01*
Y110619D01*
X939384Y106513D01*
G01X929000Y93250D02*
Y94185D01*
X938890Y104075D01*
Y106019D01*
X939384Y106513D01*
G01X933500Y93250D02*
X934807D01*
X936595Y95038D01*
X937161D01*
X942857Y100734D01*
Y105004D01*
X945240Y107387D01*
Y114083D01*
X947398Y116241D01*
Y125474D01*
X946277Y126595D01*
Y134467D01*
X948058Y136248D01*
G01X920000Y93250D02*
Y93952D01*
X924893Y98845D01*
X929059D01*
X935400Y105186D01*
Y111100D01*
X934700Y111800D01*
Y114200D01*
G01X915500Y93250D02*
X916807D01*
X923828Y100271D01*
X928005D01*
X929859Y102125D01*
X931101D01*
X934300Y105324D01*
Y108875D01*
X932375Y110800D01*
Y116722D01*
X935053Y119400D01*
Y124053D01*
X936604Y125604D01*
X938000D01*
G01X911000Y89750D02*
X909900Y88650D01*
Y85400D01*
X910000Y85300D01*
G01X911000Y82250D02*
Y84200D01*
X910000Y85200D01*
Y85300D01*
G01X938000Y89750D02*
X937642Y89392D01*
Y85562D01*
G01X938000Y82250D02*
X937642Y82608D01*
Y85562D01*
G01X924500Y89750D02*
X926106Y88144D01*
Y85252D01*
X926093Y85239D01*
G01X924500Y82250D02*
X926093Y83843D01*
Y85239D01*
G01X929000Y89750D02*
X929388Y89362D01*
Y86888D01*
X929213Y86713D01*
Y86593D01*
G01X929000Y82250D02*
X929388Y82638D01*
Y86112D01*
X929213Y86287D01*
Y86593D01*
G01X933500Y89750D02*
X934438Y88812D01*
Y86700D01*
G01X933500Y82250D02*
X934438Y83188D01*
Y86700D01*
G01X920000Y89750D02*
Y86950D01*
X919050Y86000D01*
Y85500D01*
G01X920000Y82250D02*
Y84250D01*
X919050Y85200D01*
Y85500D01*
G01X915500Y89750D02*
Y88101D01*
X913979Y86580D01*
G01X915500Y82250D02*
Y82259D01*
X913979Y83780D01*
Y86580D01*
G01X927178Y119000D02*
Y112322D01*
X931950Y107550D01*
Y105450D01*
X930375Y103875D01*
X917125D01*
X915926Y102676D01*
G01X929800Y105900D02*
X914650D01*
X908676Y99926D01*
G01X938600Y99500D02*
X941962Y102862D01*
Y106125D01*
X944365Y108528D01*
Y114446D01*
X946522Y116603D01*
Y125112D01*
X945402Y126232D01*
Y139402D01*
X947400Y141400D01*
X951100D01*
X953149Y143449D01*
Y143701D01*
G01X941339Y127953D02*
X942927Y126365D01*
Y115484D01*
X941843Y114400D01*
X941229D01*
X940051Y113222D01*
G01X939789Y121900D02*
Y120775D01*
X939751Y120737D01*
Y120182D01*
X938060Y118491D01*
X936691D01*
X934700Y116500D01*
Y114200D01*
G01X920800Y143400D02*
Y140618D01*
X921654Y139764D01*
G01X911800Y141750D02*
X915731D01*
X917717Y139764D01*
G01X915750Y133900D02*
X917717Y131933D01*
Y131890D01*
G01X919650Y137800D02*
Y137760D01*
X917717Y135827D01*
G01X927559Y153543D02*
X923622D01*
X921654Y151575D01*
G01X923620Y161450D02*
Y157483D01*
X925591Y155512D01*
G01X911820Y157500D02*
X911792D01*
X909843Y159449D01*
G01Y143701D02*
X911817Y145675D01*
Y149617D01*
G01X915750Y153500D02*
X915792D01*
X917717Y151575D01*
G01X915750Y145650D02*
X917699Y143701D01*
X917717D01*
G01X919685Y149606D02*
X917717Y147638D01*
G01X919700Y157500D02*
Y157466D01*
X921654Y155512D01*
G01X947000Y71500D02*
Y73548D01*
X948416Y74964D01*
X949102D01*
G01X956250Y67900D02*
Y65750D01*
X957600Y64400D01*
X959756D01*
X960244Y64888D01*
G01X959300Y68600D02*
X960244Y67656D01*
Y64888D01*
G01X959300Y72000D02*
X959793Y72493D01*
Y75788D01*
G01X956250Y72000D02*
Y74950D01*
X957088Y75788D01*
X959793D01*
G01X956000Y93250D02*
X958250D01*
X960000Y95000D01*
G01X953149Y127953D02*
Y126262D01*
X951561Y124674D01*
Y115439D01*
X953375Y113625D01*
Y107875D01*
X956000Y105250D01*
Y100500D01*
X960000Y96500D01*
Y95000D01*
G01X956000Y89750D02*
Y86600D01*
X956500Y86100D01*
Y85669D01*
X956687Y85482D01*
G01X956000Y82250D02*
Y84795D01*
X956687Y85482D01*
G01X942500Y89750D02*
Y86000D01*
X942800Y85700D01*
G01X942500Y82250D02*
Y85400D01*
X942800Y85700D01*
G01X947000Y89750D02*
Y87100D01*
X948200Y85900D01*
G01X947000Y82250D02*
Y84700D01*
X948200Y85900D01*
G01X951500Y89750D02*
Y87800D01*
X953301Y85999D01*
Y85793D01*
G01X951500Y82250D02*
Y83800D01*
X953301Y85601D01*
Y85793D01*
G01X944300Y98500D02*
Y104431D01*
X946478Y106609D01*
Y114083D01*
X948273Y115878D01*
Y125849D01*
X947152Y126970D01*
Y131996D01*
X950900Y135744D01*
Y139100D01*
X951564Y139764D01*
X953149D01*
G01X953000Y104500D02*
Y106234D01*
X952500Y106734D01*
Y113262D01*
X950686Y115076D01*
Y125037D01*
X951561Y125912D01*
Y128611D01*
X953149Y130199D01*
Y131890D01*
G01X960500Y105000D02*
Y109974D01*
X956200Y114274D01*
G01X952900Y98900D02*
X951800Y100000D01*
X950042D01*
X947762Y102280D01*
Y104247D01*
X949893Y106378D01*
G01X960500Y100000D02*
X958362Y102138D01*
Y110874D01*
X954736Y114500D01*
G01X975004Y100097D02*
Y101134D01*
X974529Y101609D01*
X972199D01*
X970039Y103769D01*
Y110375D01*
X968553Y111861D01*
Y114629D01*
G01X961153Y115057D02*
Y111623D01*
X962816Y109960D01*
Y103619D01*
X964448Y101987D01*
X966311D01*
X967263Y101037D01*
Y100000D01*
G01X975004Y105097D02*
Y104059D01*
X974529Y103584D01*
X973018D01*
X972014Y104588D01*
Y111194D01*
X970528Y112680D01*
Y114629D01*
G01X963128Y115057D02*
Y112442D01*
X964791Y110779D01*
Y104438D01*
X965267Y103962D01*
X966788D01*
X967263Y104437D01*
Y105000D01*
G01X949212Y127953D02*
X949722Y128463D01*
Y131306D01*
X949987Y131571D01*
G01X949212Y139764D02*
Y137402D01*
X948058Y136248D01*
G01X959055Y129921D02*
Y129922D01*
X961023Y131890D01*
G01X959055Y137795D02*
X961023Y135827D01*
G01X949700Y112900D02*
Y109906D01*
X949828Y109778D01*
G01X974803Y133858D02*
X976771Y131890D01*
G01X966929Y133858D02*
X968897Y131890D01*
G01X970866Y137795D02*
Y141733D01*
X972834Y143701D01*
G01X941339Y155512D02*
X944421D01*
X945030Y156121D01*
G01X955118Y141732D02*
Y141733D01*
X957086Y143701D01*
G01X959055Y145669D02*
X961023Y143701D01*
G01X955118Y149606D02*
X957086Y147638D01*
G01X959055Y161417D02*
Y157481D01*
X957086Y155512D01*
G01X951181Y153543D02*
Y153544D01*
X953149Y155512D01*
G01X962992Y157480D02*
X962991D01*
X961023Y155512D01*
G01X959055Y153543D02*
X961023Y151575D01*
G01X966929Y149606D02*
X964961Y147638D01*
X964960D01*
G01X974803Y157480D02*
X976771Y155512D01*
G01X974803Y141732D02*
X976771Y139764D01*
G01X970866Y145669D02*
X970865D01*
X968897Y143701D01*
G01X970866Y161417D02*
X974803D01*
X976771Y159449D01*
G01X970866Y153543D02*
Y153544D01*
X972834Y155512D01*
G01X956900Y607000D02*
X958900Y609000D01*
X1269000D01*
G01X1004178Y27605D02*
X1003111Y26538D01*
X995791D01*
X994949Y25696D01*
X986377D01*
X985579Y26494D01*
G01X1004178Y23605D02*
X1003220Y24563D01*
X996610D01*
X995768Y23721D01*
X986131D01*
X985403Y22993D01*
G01X1015079Y28550D02*
X1013603D01*
X1011656Y26603D01*
X1008680D01*
X1007678Y27605D01*
G01X1005774Y31854D02*
Y31123D01*
X1007678Y29219D01*
Y27605D01*
G01Y23605D02*
Y21716D01*
X1005750Y19788D01*
G01X1015079Y25990D02*
X1013837D01*
X1012475Y24628D01*
X1008701D01*
X1007678Y23605D01*
G01X994700Y101050D02*
Y93400D01*
X997400Y90700D01*
X1050100D01*
X1057000Y97600D01*
Y107700D01*
G01X994700Y108600D02*
Y104550D01*
G01X1003100D02*
Y106199D01*
X1002037Y107262D01*
Y110849D01*
X998805Y114081D01*
Y115529D01*
X996875Y117459D01*
G01X990552Y104550D02*
X989539Y105563D01*
Y112152D01*
X986105Y115586D01*
Y116251D01*
G01X999000Y104550D02*
Y106200D01*
X1000062Y107262D01*
Y110030D01*
X996830Y113262D01*
Y114710D01*
X995478Y116062D01*
G01X985734Y113163D02*
X987564Y111333D01*
Y105562D01*
X986552Y104550D01*
G01X979364Y112812D02*
Y104293D01*
X980170Y103487D01*
X981525D01*
X982000Y103962D01*
Y105000D01*
G01X977389Y112812D02*
Y103474D01*
X979351Y101512D01*
X981525D01*
X982000Y101037D01*
Y100000D01*
G01X991332Y114300D02*
X994700Y110932D01*
Y108600D01*
G01X982677Y133858D02*
X980708Y135827D01*
G01X985734Y113163D02*
X984130Y114767D01*
Y116251D01*
G01X984760Y112189D02*
X985734Y113163D01*
G01X990551Y133858D02*
X990550D01*
X988582Y131890D01*
G01X982677Y141732D02*
X984645Y139764D01*
G01X978740Y161417D02*
X980708Y159449D01*
G01X982632Y157480D02*
X980708Y155556D01*
Y155512D01*
G01X987039Y153765D02*
X988685D01*
X988899Y153979D01*
X991608D01*
G01X988582Y151575D02*
X990253D01*
X991608Y152930D01*
Y153979D01*
G01X978740Y153543D02*
X980708Y151575D01*
G01X982700Y149600D02*
X980424D01*
X979120Y148296D01*
Y146050D01*
X976771Y143701D01*
G01X1323195Y161642D02*
X1321532Y159979D01*
X1315130D01*
X1306522Y151371D01*
Y120543D01*
X1305124Y119145D01*
Y98103D01*
X1301520Y94499D01*
Y23351D01*
X1286339Y8170D01*
X1112918D01*
X1094771Y-9977D01*
X1061153D01*
X1056151Y-4975D01*
X1022711D01*
G01X1033554Y30216D02*
X1033665Y30105D01*
X1040161D01*
X1043666Y26600D01*
X1044935D01*
X1051450Y33115D01*
G01X1025679Y23435D02*
X1031029D01*
X1031991Y22473D01*
G01X1044147Y10340D02*
X1041868Y12619D01*
Y16102D01*
X1041322Y16648D01*
X1040632D01*
X1037764Y19516D01*
X1036615D01*
X1033658Y22473D01*
X1031991D01*
G01X1044161Y17818D02*
X1044111Y17868D01*
X1043000D01*
X1042320Y18548D01*
X1040748D01*
X1036989Y22307D01*
G01X1025679Y25990D02*
X1033306D01*
X1036989Y22307D01*
G01X1039500Y56701D02*
X1035416Y60785D01*
X1028285D01*
X1026125Y58625D01*
Y57650D01*
G01X1039500Y56500D02*
Y56701D01*
G01D02*
Y60302D01*
X1040241Y61043D01*
G01X1030000Y50150D02*
X1031495Y48655D01*
X1033238D01*
X1033517Y48934D01*
G01X1030000Y50150D02*
Y52047D01*
X1027385Y54662D01*
X1021775D01*
X1020676Y53563D01*
G01X1020596Y57597D02*
Y53643D01*
X1020676Y53563D01*
G01X1037900Y108500D02*
X1037815Y108415D01*
Y104700D01*
G01X1041300Y108500D02*
Y112249D01*
X1041249Y112300D01*
G01X1030883Y112238D02*
Y108438D01*
G01X1077550Y3500D02*
Y-250D01*
X1074900Y-2900D01*
X1071299D01*
X1069700Y-1301D01*
Y4550D01*
G01X1062044Y-4173D02*
X1063064Y-3153D01*
Y4864D01*
X1066038Y7838D01*
X1068221Y10026D01*
X1068301Y10106D01*
X1070302Y12110D01*
G01X1065620Y-4335D02*
X1065039Y-3754D01*
Y1949D01*
G01D02*
X1066272D01*
G01X1065039D02*
Y4045D01*
X1067436Y6442D01*
X1068013Y7020D01*
X1069041Y8050D01*
X1069700D01*
G01X1074050Y3500D02*
Y7600D01*
G01Y3500D02*
Y450D01*
X1072800Y-800D01*
G01X1379473Y163528D02*
X1369151D01*
X1367770Y164909D01*
X1354860D01*
X1351991Y167778D01*
X1319250D01*
X1305075Y153603D01*
Y121112D01*
X1303699Y119736D01*
Y98694D01*
X1300095Y95090D01*
Y23942D01*
X1285748Y9595D01*
X1112327D01*
X1094180Y-8552D01*
X1061852D01*
X1060736Y-7436D01*
X1060692D01*
X1053742Y-486D01*
Y10313D01*
X1055367Y11938D01*
X1058962D01*
X1060800Y10100D01*
G01X1368540Y169284D02*
X1318255D01*
X1303650Y154679D01*
Y121703D01*
X1302274Y120327D01*
Y99285D01*
X1298670Y95681D01*
Y24533D01*
X1285157Y11020D01*
X1111736D01*
X1093778Y-6938D01*
X1062254D01*
X1061327Y-6011D01*
X1061283D01*
X1056500Y-1228D01*
Y9800D01*
X1056200Y10100D01*
G01X1069394Y13018D02*
X1070302Y12110D01*
G01D02*
X1072564Y14375D01*
X1079979D01*
X1082115Y12239D01*
X1103439D01*
X1107000Y15800D01*
X1228800D01*
X1249800Y36800D01*
Y71300D01*
X1256435Y77935D01*
Y84764D01*
G01X1069700Y8050D02*
Y8710D01*
X1070699Y9712D01*
X1073385Y12400D01*
X1074150D01*
G01X1046950Y33115D02*
Y31715D01*
X1044050Y28815D01*
G01X1044147Y10340D02*
X1046867D01*
X1047072Y10545D01*
X1047849D01*
X1049161Y11857D01*
G01X1044161Y17818D02*
X1044211Y17868D01*
X1045999D01*
X1046488Y18357D01*
X1048662D01*
G01X1073250Y40000D02*
X1077868D01*
X1084360Y46492D01*
X1087983D01*
X1088005Y46514D01*
Y46541D01*
G01X1068750Y28000D02*
X1066603D01*
X1065657Y28946D01*
G01X1047500Y41500D02*
Y37165D01*
X1046950Y36615D01*
G01X1051000Y41500D02*
Y37065D01*
X1051450Y36615D01*
G01X1076970Y30411D02*
X1075559Y29000D01*
X1073250D01*
G01X1052600Y14400D02*
X1053900Y15700D01*
X1060058D01*
X1060635Y15123D01*
X1062157D01*
X1062158Y15124D01*
X1063924D01*
X1065800Y17000D01*
X1068750D01*
G01X1052744Y48446D02*
X1051482Y49708D01*
Y54990D01*
X1049772Y56700D01*
Y57259D01*
G01X1052744Y48446D02*
X1061598D01*
X1061975Y48823D01*
G01X1049470Y53749D02*
X1049969Y53250D01*
Y47996D01*
X1052052Y45913D01*
X1059587D01*
X1061177Y44323D01*
X1061975D01*
G01X1065475Y48823D02*
X1067903D01*
X1068862Y49782D01*
X1072167D01*
G01D02*
X1076886D01*
X1083021Y55917D01*
X1088287D01*
G01X1065475Y44323D02*
X1069058D01*
X1069889Y45154D01*
G01D02*
X1071735Y47000D01*
X1076954D01*
X1081295Y51341D01*
X1096381D01*
X1096496Y51226D01*
G01X1057000Y107700D02*
Y280450D01*
X1087550Y311000D01*
X1281900D01*
X1284505Y308395D01*
G01X1077550Y7600D02*
X1082150Y3000D01*
X1087902D01*
X1088503Y3601D01*
G01X1259387Y79252D02*
Y78871D01*
X1251225Y70709D01*
Y35209D01*
X1230391Y14375D01*
X1108559D01*
X1097884Y3700D01*
X1088602D01*
X1088503Y3601D01*
G01X1085500Y-3000D02*
X1084901D01*
X1082162Y-261D01*
Y338D01*
X1079000Y3500D01*
X1077550D01*
G01X1259387Y64292D02*
X1256692D01*
X1252650Y60250D01*
Y34618D01*
X1230981Y12949D01*
X1109149D01*
X1093200Y-3000D01*
X1085500D01*
G01X1077650Y12400D02*
Y7700D01*
X1077550Y7600D01*
G01X1086715Y27686D02*
X1087323D01*
X1089999Y30362D01*
X1092094D01*
G01X1083500Y25500D02*
X1082457Y26543D01*
X1080496D01*
X1080017Y27022D01*
G01X1313607Y664000D02*
X1312954D01*
X1309691Y660737D01*
X1289913D01*
X1289912Y660736D01*
X1288732D01*
X1171747Y777721D01*
Y814500D01*
G01X1310207Y664000D02*
X1308369Y662162D01*
X1289322D01*
X1176738Y774746D01*
Y806500D01*
G01X1317007Y664000D02*
X1312319Y659312D01*
X1290504D01*
X1290503Y659311D01*
X1288141D01*
X1168800Y778652D01*
Y820453D01*
X1168607Y820646D01*
Y823010D01*
G01X1173623Y889470D02*
Y882823D01*
X1171747Y880947D01*
Y814500D01*
G01X1176772Y889470D02*
Y852204D01*
X1173172Y848604D01*
Y822627D01*
X1176738Y819061D01*
Y806500D01*
G01X1170473Y889470D02*
Y874304D01*
X1168607Y872438D01*
Y834500D01*
G01Y823010D02*
Y834500D01*
G01X1198134Y420766D02*
X1201000Y417900D01*
G01X1196600Y416200D02*
X1182300D01*
X1179723Y418777D01*
G01X1220867Y889470D02*
Y879746D01*
X1222349Y878264D01*
Y870333D01*
X1217267Y865251D01*
Y740633D01*
X1286800Y671100D01*
G01X1217717Y889470D02*
Y883083D01*
X1219455Y881345D01*
Y879327D01*
X1220924Y877858D01*
Y870924D01*
X1215842Y865842D01*
Y739459D01*
X1288301Y667000D01*
X1292000D01*
G01X1255000Y317300D02*
Y323000D01*
G01X1272500Y350000D02*
X1272000Y349500D01*
Y341500D01*
X1274030Y339470D01*
G01X1275060Y345690D02*
Y343940D01*
X1280836Y338164D01*
G01X1277620Y349500D02*
Y346380D01*
X1286000Y338000D01*
X1295000D01*
G01X1264820Y356000D02*
Y349320D01*
G01X1258000Y421500D02*
Y408920D01*
X1264820Y402100D01*
Y356000D01*
G01X1273500Y406500D02*
Y400500D01*
G01X1300000Y637000D02*
X1272000Y609000D01*
X1269000D01*
G01X1284505Y308395D02*
X1288900Y304000D01*
G01X1281900Y346580D02*
X1282170D01*
X1288250Y340500D01*
X1307500D01*
G01X1290125Y382875D02*
X1296500Y376500D01*
X1298500D01*
G01X1297625Y382375D02*
X1297750Y382500D01*
X1311000D01*
X1312839Y384339D01*
G01X1296500Y386500D02*
X1295000Y385000D01*
Y381500D01*
X1297000Y379500D01*
X1305500D01*
G01X1301000Y618500D02*
X1305432Y622932D01*
G01X1302000Y695500D02*
X1295779Y689279D01*
Y676356D01*
X1299973Y672162D01*
X1319508D01*
X1324545Y667125D01*
Y642045D01*
X1305432Y622932D01*
G01X1296264Y645191D02*
X1294977D01*
G01D02*
Y648877D01*
X1297400Y651300D01*
G01X1291800Y637751D02*
X1293002D01*
G01D02*
Y648848D01*
X1290550Y651300D01*
G01X1302128Y680617D02*
X1301400D01*
X1298017Y684000D01*
G01X1306128Y680617D02*
X1304000Y682745D01*
Y686245D01*
X1303440Y686805D01*
Y688687D01*
X1303709Y688956D01*
G01X1297500Y664000D02*
X1294500Y667000D01*
X1292000D01*
G01X1310128Y680617D02*
Y682628D01*
X1311793Y684293D01*
X1312132D01*
G01X1298000Y710750D02*
X1294354Y707104D01*
Y675765D01*
X1299382Y670737D01*
X1318917D01*
X1323120Y666534D01*
Y647120D01*
X1314422Y638422D01*
G01X1302128Y685500D02*
X1299517D01*
X1298017Y684000D01*
G01X1307000Y686500D02*
X1304544Y688956D01*
X1303709D01*
G01X1298000Y707250D02*
Y703500D01*
G01D02*
X1298750D01*
X1302000Y706750D01*
G01D02*
X1307631D01*
X1307662Y706719D01*
G01X1310900Y713650D02*
X1311250Y714000D01*
X1315000D01*
G01X1310222Y706719D02*
Y709500D01*
X1310722Y710000D01*
X1313000D01*
X1315000Y712000D01*
Y714000D01*
G01X1314628Y733000D02*
X1312790Y734838D01*
X1298500D01*
G01X1310100Y726150D02*
X1306300D01*
X1305650Y725500D01*
G01X1310500Y723000D02*
X1306500D01*
X1305650Y723850D01*
Y725500D01*
G01X1310900Y717150D02*
X1316350D01*
X1317384Y716116D01*
Y708739D01*
X1317000Y708355D01*
Y700111D01*
X1320251Y696860D01*
Y690751D01*
X1319500Y690000D01*
G01X1325900Y717650D02*
X1318087D01*
X1316000Y719737D01*
X1309148D01*
X1308911Y719500D01*
X1298500D01*
X1295714Y716714D01*
G01X1323195Y161642D02*
X1348785D01*
G01X1314128Y680617D02*
X1317848D01*
X1318117Y680886D01*
G01X1315000Y686500D02*
X1315413Y686087D01*
Y685155D01*
X1318117Y682451D01*
Y680886D01*
G01X1330128Y680617D02*
X1331617D01*
X1333052Y682052D01*
Y686020D01*
G01X1327200Y661800D02*
X1327700Y662300D01*
Y664300D01*
X1332400Y669000D01*
X1339500D01*
X1344200Y673700D01*
X1345541D01*
X1347788Y675947D01*
Y677288D01*
X1347900Y677400D01*
Y689150D01*
X1346900Y690150D01*
G01X1322128Y680617D02*
Y683598D01*
X1321928Y683798D01*
G01X1338128Y680617D02*
X1342617D01*
X1343000Y681000D01*
G01X1339934Y683832D02*
X1342668D01*
X1343005Y683495D01*
Y681005D01*
X1343000Y681000D01*
G01X1331000Y658200D02*
Y662000D01*
G01X1326128Y680617D02*
Y684990D01*
X1326758Y685620D01*
Y686678D01*
G01X1326128Y674000D02*
X1327966Y672162D01*
X1330000D01*
G01X1340000Y674000D02*
X1338162Y672162D01*
X1330000D01*
G01X1329500Y684667D02*
X1330833Y686000D01*
X1333000D01*
X1333020Y686020D01*
X1333052D01*
G01X1321928Y683798D02*
X1320251Y685475D01*
Y689249D01*
X1319500Y690000D01*
G01X1312900Y690150D02*
X1313949D01*
X1316838Y687261D01*
Y686329D01*
X1318500Y684667D01*
G01X1329900Y717650D02*
X1331000D01*
X1331662Y718312D01*
X1336000D01*
X1337000Y717312D01*
Y716168D01*
X1335093Y714261D01*
Y711435D01*
X1335338Y711190D01*
Y708500D01*
X1332562Y705724D01*
Y699392D01*
X1336760Y695194D01*
Y690959D01*
X1336362Y690561D01*
Y689039D01*
X1337439Y687962D01*
X1337538D01*
X1339212Y686288D01*
Y685993D01*
X1339934Y685271D01*
Y683832D01*
G01X1330400Y690150D02*
X1333350D01*
X1334937Y688563D01*
Y687447D01*
X1336795Y685589D01*
Y685141D01*
G01X1336000Y705250D02*
Y707146D01*
X1336763Y707909D01*
Y712134D01*
X1337338Y712709D01*
G01X1341662Y707219D02*
Y713388D01*
X1340900Y714150D01*
G01D02*
X1338779D01*
X1337338Y712709D01*
G01X1325900Y714150D02*
X1322950D01*
X1322300Y713500D01*
G01X1319500Y709250D02*
Y710700D01*
X1322300Y713500D01*
G01X1325900Y714150D02*
X1325162Y713412D01*
Y707219D01*
G01X1344222D02*
Y704778D01*
X1344919Y704081D01*
X1350567D01*
X1352000Y705514D01*
Y708500D01*
G01X1344900Y714150D02*
X1345588Y714838D01*
X1350162D01*
X1352000Y713000D01*
Y708500D01*
G01X1327722Y707219D02*
Y709722D01*
X1329000Y711000D01*
X1332159D01*
X1333659Y712500D01*
Y716054D01*
X1333639Y716074D01*
G01X1329900Y714150D02*
X1331824Y716074D01*
X1333639D01*
G01X1312900Y693650D02*
X1316150D01*
X1317500Y695000D01*
G01X1312782Y700219D02*
X1314876D01*
X1317500Y697595D01*
Y695000D01*
G01X1330400Y693650D02*
X1333840D01*
X1334195Y694005D01*
G01X1330282Y700719D02*
Y697718D01*
X1331000Y697000D01*
X1332938D01*
X1334195Y695743D01*
Y694005D01*
G01X1314628Y726117D02*
X1317611D01*
X1318228Y725500D01*
G01X1315000Y723000D02*
X1317500D01*
X1318228Y723728D01*
Y725500D01*
G01X1334128Y726117D02*
X1331617D01*
X1330000Y724500D01*
G01X1333500Y723000D02*
X1331000D01*
X1330000Y724000D01*
Y724500D01*
G01X1334128Y732667D02*
X1332975Y733820D01*
Y739975D01*
X1352500Y759500D01*
G01X1344900Y717650D02*
Y721170D01*
X1344237Y721833D01*
G01X1325600Y722987D02*
X1327425Y721162D01*
X1338261D01*
X1339099Y722000D01*
X1344070D01*
X1344237Y721833D01*
G01X1325500Y726250D02*
Y723087D01*
X1325600Y722987D01*
G01X1342000Y732500D02*
X1355000Y719500D01*
Y716000D01*
G01X1337500Y723000D02*
X1338083D01*
X1338508Y723425D01*
X1340925D01*
X1342000Y724500D01*
Y726500D01*
G01X1338128Y726117D02*
X1338511Y726500D01*
X1342000D01*
G01X1340500Y742500D02*
X1338128Y740128D01*
Y738000D01*
G01D02*
Y732872D01*
G01X1330128Y732667D02*
X1331550Y734089D01*
Y740566D01*
X1341492Y750508D01*
G01X1340900Y717650D02*
X1338813Y719737D01*
X1326000D01*
X1325974Y719763D01*
X1320625D01*
X1320500Y719888D01*
G01X1353150Y889470D02*
Y883350D01*
X1349500Y879700D01*
Y846500D01*
X1357900Y838100D01*
Y836001D01*
X1358015Y835886D01*
Y827415D01*
X1346877Y816277D01*
X1333800D01*
X1331123Y813600D01*
Y795877D01*
X1356100Y770900D01*
Y763100D01*
X1352500Y759500D01*
G01X1341492Y750508D02*
X1340500Y751500D01*
G01X1329700Y817400D02*
X1329500Y817200D01*
Y814962D01*
X1329698Y814764D01*
Y795202D01*
X1354675Y770225D01*
Y763691D01*
X1341492Y750508D01*
G01X1350000Y889470D02*
Y881438D01*
X1348625Y880063D01*
Y874841D01*
X1348075Y874291D01*
Y845909D01*
X1356475Y837509D01*
Y835410D01*
X1356590Y835295D01*
Y828190D01*
X1346102Y817702D01*
X1331602D01*
X1331300Y817400D01*
X1329700D01*
G01X1378289Y169235D02*
X1378581Y168943D01*
X1383164D01*
G01X1378289Y169235D02*
X1374174Y173350D01*
Y175745D01*
G01X1374789Y169235D02*
X1374740Y169284D01*
X1368540D01*
G01X1385467Y180543D02*
X1380669Y175745D01*
X1376734D01*
G01X1365804Y185197D02*
X1365933Y185326D01*
X1369649D01*
X1371614Y183361D01*
Y182245D01*
G01X1365804Y185197D02*
Y189733D01*
G01X1364000Y299500D02*
Y280500D01*
G01X1351500Y671200D02*
Y675000D01*
G01X1346900Y690150D02*
X1351650D01*
X1355000Y693500D01*
Y716000D01*
G01X1346782Y700719D02*
X1351281D01*
X1352000Y700000D01*
Y698000D01*
G01X1346900Y693650D02*
X1350150D01*
X1352000Y695500D01*
Y698000D01*
G01X1353500Y758500D02*
X1352500Y759500D01*
G54D69*
X1030000Y50150D03*
X1026125Y57650D03*
X1033875D03*
M02*
